FILE_TYPE = MACRO_DRAWING;
SET COLOR_WIRE YELLOW;
SET COLOR_PROP MONO;
SET COLOR_DOT WHITE;
SET COLOR_ARC YELLOW;
SET COLOR_BODY GREEN;
SET COLOR_NOTE MONO;
SET PROP_DISPLAY VALUE;
SET PAGE_NUMBER P77;
FORCEADD OFFPAGE..3
(1600 5100);
FORCEPROP 2 LAST $XR0 57 
J 0
(1814 5100);
DISPLAY 0.638298 (1814 5100);
PAINT MONO (1814 5100);
FORCEPROP 2 LAST $XR1 78 
J 0
(1904 5100);
DISPLAY 0.638298 (1904 5100);
PAINT MONO (1904 5100);
FORCEPROP 2 LAST CDS_LIB mstr_standard
J 0
(1600 5100);
DISPLAY 0.787234 (1600 5100);
PAINT MONO (1600 5100);
DISPLAY INVISIBLE (1600 5100);
FORCEPROP 1 LAST OFFPAGE TRUE
J 0
(1925 4975);
DISPLAY 0.936170 (1925 4975);
PAINT GREEN (1925 4975);
DISPLAY INVISIBLE (1925 4975);
FORCEPROP 1 LAST COMMENT_BODY TRUE
J 0
(1550 5000);
DISPLAY 0.936170 (1550 5000);
PAINT GREEN (1550 5000);
DISPLAY INVISIBLE (1550 5000);
FORCEPROP 2 LAST PATH I1
J 0
(1800 5175);
DISPLAY 0.787234 (1800 5175);
PAINT MONO (1800 5175);
DISPLAY INVISIBLE (1800 5175);
FORCEADD TAP..6
R 2
(700 4750);
FORCEPROP 3 LASTPIN (650 4750) SIG_NAME M_G_DQS_DP<14>
J 0
(660 4760);
DISPLAY 0.659574 (660 4760);
PAINT MONO (660 4760);
DISPLAY INVISIBLE (660 4760);
FORCEPROP 1 LASTPIN (650 4750) BN 14
J 2
(700 4760);
DISPLAY 0.617021 (700 4760);
PAINT PINK (700 4760);
FORCEPROP 2 LAST CDS_LIB mstr_standard
J 0
(700 4750);
DISPLAY 0.787234 (700 4750);
PAINT MONO (700 4750);
DISPLAY INVISIBLE (700 4750);
FORCEPROP 1 LAST BODY_TYPE PLUMBING
J 2
(700 4700);
DISPLAY 1.234043 (700 4700);
PAINT GREEN (700 4700);
DISPLAY INVISIBLE (700 4700);
FORCEPROP 1 LAST HDL_TAP TRUE
J 2
(375 4625);
DISPLAY 1.234043 (375 4625);
PAINT GREEN (375 4625);
DISPLAY INVISIBLE (375 4625);
FORCEPROP 1 LAST PATH I10
J 2
(700 4750);
DISPLAY 0.936170 (700 4750);
PAINT GREEN (700 4750);
DISPLAY INVISIBLE (700 4750);
FORCEADD TAP..6
R 2
(-1625 1775);
FORCEPROP 3 LASTPIN (-1675 1775) SIG_NAME M_G_DQ<11>
J 0
(-1665 1785);
DISPLAY 0.659574 (-1665 1785);
PAINT MONO (-1665 1785);
DISPLAY INVISIBLE (-1665 1785);
FORCEPROP 1 LASTPIN (-1675 1775) BN 11
J 2
(-1625 1785);
DISPLAY 0.617021 (-1625 1785);
PAINT PINK (-1625 1785);
FORCEPROP 2 LAST CDS_LIB mstr_standard
J 2
(-1625 1775);
DISPLAY 0.787234 (-1625 1775);
PAINT MONO (-1625 1775);
DISPLAY INVISIBLE (-1625 1775);
FORCEPROP 1 LAST BODY_TYPE PLUMBING
J 2
(-1625 1725);
DISPLAY 1.234043 (-1625 1725);
PAINT GREEN (-1625 1725);
DISPLAY INVISIBLE (-1625 1725);
FORCEPROP 1 LAST HDL_TAP TRUE
J 2
(-1950 1650);
DISPLAY 1.234043 (-1950 1650);
PAINT GREEN (-1950 1650);
DISPLAY INVISIBLE (-1950 1650);
FORCEPROP 1 LAST PATH I100
J 2
(-1625 1775);
DISPLAY 0.936170 (-1625 1775);
PAINT GREEN (-1625 1775);
DISPLAY INVISIBLE (-1625 1775);
FORCEADD TAP..6
R 2
(-1625 1725);
FORCEPROP 3 LASTPIN (-1675 1725) SIG_NAME M_G_DQ<8>
J 0
(-1665 1735);
DISPLAY 0.659574 (-1665 1735);
PAINT MONO (-1665 1735);
DISPLAY INVISIBLE (-1665 1735);
FORCEPROP 1 LASTPIN (-1675 1725) BN 8
J 2
(-1625 1735);
DISPLAY 0.617021 (-1625 1735);
PAINT PINK (-1625 1735);
FORCEPROP 2 LAST CDS_LIB mstr_standard
J 2
(-1625 1725);
DISPLAY 0.787234 (-1625 1725);
PAINT MONO (-1625 1725);
DISPLAY INVISIBLE (-1625 1725);
FORCEPROP 1 LAST BODY_TYPE PLUMBING
J 2
(-1625 1675);
DISPLAY 1.234043 (-1625 1675);
PAINT GREEN (-1625 1675);
DISPLAY INVISIBLE (-1625 1675);
FORCEPROP 1 LAST HDL_TAP TRUE
J 2
(-1950 1600);
DISPLAY 1.234043 (-1950 1600);
PAINT GREEN (-1950 1600);
DISPLAY INVISIBLE (-1950 1600);
FORCEPROP 1 LAST PATH I101
J 2
(-1625 1725);
DISPLAY 0.936170 (-1625 1725);
PAINT GREEN (-1625 1725);
DISPLAY INVISIBLE (-1625 1725);
FORCEADD TAP..6
R 2
(-1625 1675);
FORCEPROP 3 LASTPIN (-1675 1675) SIG_NAME M_G_DQ<9>
J 0
(-1665 1685);
DISPLAY 0.659574 (-1665 1685);
PAINT MONO (-1665 1685);
DISPLAY INVISIBLE (-1665 1685);
FORCEPROP 1 LASTPIN (-1675 1675) BN 9
J 2
(-1625 1685);
DISPLAY 0.617021 (-1625 1685);
PAINT PINK (-1625 1685);
FORCEPROP 2 LAST CDS_LIB mstr_standard
J 2
(-1625 1675);
DISPLAY 0.787234 (-1625 1675);
PAINT MONO (-1625 1675);
DISPLAY INVISIBLE (-1625 1675);
FORCEPROP 1 LAST BODY_TYPE PLUMBING
J 2
(-1625 1625);
DISPLAY 1.234043 (-1625 1625);
PAINT GREEN (-1625 1625);
DISPLAY INVISIBLE (-1625 1625);
FORCEPROP 1 LAST HDL_TAP TRUE
J 2
(-1950 1550);
DISPLAY 1.234043 (-1950 1550);
PAINT GREEN (-1950 1550);
DISPLAY INVISIBLE (-1950 1550);
FORCEPROP 1 LAST PATH I102
J 2
(-1625 1675);
DISPLAY 0.936170 (-1625 1675);
PAINT GREEN (-1625 1675);
DISPLAY INVISIBLE (-1625 1675);
FORCEADD TAP..6
R 2
(-1625 1575);
FORCEPROP 3 LASTPIN (-1675 1575) SIG_NAME M_G_DQ<7>
J 0
(-1665 1585);
DISPLAY 0.659574 (-1665 1585);
PAINT MONO (-1665 1585);
DISPLAY INVISIBLE (-1665 1585);
FORCEPROP 1 LASTPIN (-1675 1575) BN 7
J 2
(-1625 1585);
DISPLAY 0.617021 (-1625 1585);
PAINT PINK (-1625 1585);
FORCEPROP 2 LAST CDS_LIB mstr_standard
J 2
(-1625 1575);
DISPLAY 0.787234 (-1625 1575);
PAINT MONO (-1625 1575);
DISPLAY INVISIBLE (-1625 1575);
FORCEPROP 1 LAST BODY_TYPE PLUMBING
J 2
(-1625 1525);
DISPLAY 1.234043 (-1625 1525);
PAINT GREEN (-1625 1525);
DISPLAY INVISIBLE (-1625 1525);
FORCEPROP 1 LAST HDL_TAP TRUE
J 2
(-1950 1450);
DISPLAY 1.234043 (-1950 1450);
PAINT GREEN (-1950 1450);
DISPLAY INVISIBLE (-1950 1450);
FORCEPROP 1 LAST PATH I103
J 2
(-1625 1575);
DISPLAY 0.936170 (-1625 1575);
PAINT GREEN (-1625 1575);
DISPLAY INVISIBLE (-1625 1575);
FORCEADD TAP..6
R 2
(-1625 1625);
FORCEPROP 3 LASTPIN (-1675 1625) SIG_NAME M_G_DQ<6>
J 0
(-1665 1635);
DISPLAY 0.659574 (-1665 1635);
PAINT MONO (-1665 1635);
DISPLAY INVISIBLE (-1665 1635);
FORCEPROP 1 LASTPIN (-1675 1625) BN 6
J 2
(-1625 1635);
DISPLAY 0.617021 (-1625 1635);
PAINT PINK (-1625 1635);
FORCEPROP 2 LAST CDS_LIB mstr_standard
J 2
(-1625 1625);
DISPLAY 0.787234 (-1625 1625);
PAINT MONO (-1625 1625);
DISPLAY INVISIBLE (-1625 1625);
FORCEPROP 1 LAST BODY_TYPE PLUMBING
J 2
(-1625 1575);
DISPLAY 1.234043 (-1625 1575);
PAINT GREEN (-1625 1575);
DISPLAY INVISIBLE (-1625 1575);
FORCEPROP 1 LAST HDL_TAP TRUE
J 2
(-1950 1500);
DISPLAY 1.234043 (-1950 1500);
PAINT GREEN (-1950 1500);
DISPLAY INVISIBLE (-1950 1500);
FORCEPROP 1 LAST PATH I104
J 2
(-1625 1625);
DISPLAY 0.936170 (-1625 1625);
PAINT GREEN (-1625 1625);
DISPLAY INVISIBLE (-1625 1625);
FORCEADD TAP..6
R 2
(-1625 1425);
FORCEPROP 3 LASTPIN (-1675 1425) SIG_NAME M_G_DQ<2>
J 0
(-1665 1435);
DISPLAY 0.659574 (-1665 1435);
PAINT MONO (-1665 1435);
DISPLAY INVISIBLE (-1665 1435);
FORCEPROP 1 LASTPIN (-1675 1425) BN 2
J 2
(-1625 1435);
DISPLAY 0.617021 (-1625 1435);
PAINT PINK (-1625 1435);
FORCEPROP 2 LAST CDS_LIB mstr_standard
J 2
(-1625 1425);
DISPLAY 0.787234 (-1625 1425);
PAINT MONO (-1625 1425);
DISPLAY INVISIBLE (-1625 1425);
FORCEPROP 1 LAST BODY_TYPE PLUMBING
J 2
(-1625 1375);
DISPLAY 1.234043 (-1625 1375);
PAINT GREEN (-1625 1375);
DISPLAY INVISIBLE (-1625 1375);
FORCEPROP 1 LAST HDL_TAP TRUE
J 2
(-1950 1300);
DISPLAY 1.234043 (-1950 1300);
PAINT GREEN (-1950 1300);
DISPLAY INVISIBLE (-1950 1300);
FORCEPROP 1 LAST PATH I105
J 2
(-1625 1425);
DISPLAY 0.936170 (-1625 1425);
PAINT GREEN (-1625 1425);
DISPLAY INVISIBLE (-1625 1425);
FORCEADD TAP..6
R 2
(-1625 1475);
FORCEPROP 3 LASTPIN (-1675 1475) SIG_NAME M_G_DQ<5>
J 0
(-1665 1485);
DISPLAY 0.659574 (-1665 1485);
PAINT MONO (-1665 1485);
DISPLAY INVISIBLE (-1665 1485);
FORCEPROP 1 LASTPIN (-1675 1475) BN 5
J 2
(-1625 1485);
DISPLAY 0.617021 (-1625 1485);
PAINT PINK (-1625 1485);
FORCEPROP 2 LAST CDS_LIB mstr_standard
J 2
(-1625 1475);
DISPLAY 0.787234 (-1625 1475);
PAINT MONO (-1625 1475);
DISPLAY INVISIBLE (-1625 1475);
FORCEPROP 1 LAST BODY_TYPE PLUMBING
J 2
(-1625 1425);
DISPLAY 1.234043 (-1625 1425);
PAINT GREEN (-1625 1425);
DISPLAY INVISIBLE (-1625 1425);
FORCEPROP 1 LAST HDL_TAP TRUE
J 2
(-1950 1350);
DISPLAY 1.234043 (-1950 1350);
PAINT GREEN (-1950 1350);
DISPLAY INVISIBLE (-1950 1350);
FORCEPROP 1 LAST PATH I106
J 2
(-1625 1475);
DISPLAY 0.936170 (-1625 1475);
PAINT GREEN (-1625 1475);
DISPLAY INVISIBLE (-1625 1475);
FORCEADD TAP..6
R 2
(-1625 1525);
FORCEPROP 3 LASTPIN (-1675 1525) SIG_NAME M_G_DQ<4>
J 0
(-1665 1535);
DISPLAY 0.659574 (-1665 1535);
PAINT MONO (-1665 1535);
DISPLAY INVISIBLE (-1665 1535);
FORCEPROP 1 LASTPIN (-1675 1525) BN 4
J 2
(-1625 1535);
DISPLAY 0.617021 (-1625 1535);
PAINT PINK (-1625 1535);
FORCEPROP 2 LAST CDS_LIB mstr_standard
J 2
(-1625 1525);
DISPLAY 0.787234 (-1625 1525);
PAINT MONO (-1625 1525);
DISPLAY INVISIBLE (-1625 1525);
FORCEPROP 1 LAST BODY_TYPE PLUMBING
J 2
(-1625 1475);
DISPLAY 1.234043 (-1625 1475);
PAINT GREEN (-1625 1475);
DISPLAY INVISIBLE (-1625 1475);
FORCEPROP 1 LAST HDL_TAP TRUE
J 2
(-1950 1400);
DISPLAY 1.234043 (-1950 1400);
PAINT GREEN (-1950 1400);
DISPLAY INVISIBLE (-1950 1400);
FORCEPROP 1 LAST PATH I107
J 2
(-1625 1525);
DISPLAY 0.936170 (-1625 1525);
PAINT GREEN (-1625 1525);
DISPLAY INVISIBLE (-1625 1525);
FORCEADD TAP..6
R 2
(-1625 1325);
FORCEPROP 3 LASTPIN (-1675 1325) SIG_NAME M_G_DQ<0>
J 0
(-1665 1335);
DISPLAY 0.659574 (-1665 1335);
PAINT MONO (-1665 1335);
DISPLAY INVISIBLE (-1665 1335);
FORCEPROP 1 LASTPIN (-1675 1325) BN 0
J 2
(-1625 1335);
DISPLAY 0.617021 (-1625 1335);
PAINT PINK (-1625 1335);
FORCEPROP 2 LAST CDS_LIB mstr_standard
J 2
(-1625 1325);
DISPLAY 0.787234 (-1625 1325);
PAINT MONO (-1625 1325);
DISPLAY INVISIBLE (-1625 1325);
FORCEPROP 1 LAST BODY_TYPE PLUMBING
J 2
(-1625 1275);
DISPLAY 1.234043 (-1625 1275);
PAINT GREEN (-1625 1275);
DISPLAY INVISIBLE (-1625 1275);
FORCEPROP 1 LAST HDL_TAP TRUE
J 2
(-1950 1200);
DISPLAY 1.234043 (-1950 1200);
PAINT GREEN (-1950 1200);
DISPLAY INVISIBLE (-1950 1200);
FORCEPROP 1 LAST PATH I108
J 2
(-1625 1325);
DISPLAY 0.936170 (-1625 1325);
PAINT GREEN (-1625 1325);
DISPLAY INVISIBLE (-1625 1325);
FORCEADD TAP..6
R 2
(-1625 1275);
FORCEPROP 3 LASTPIN (-1675 1275) SIG_NAME M_G_DQ<1>
J 0
(-1665 1285);
DISPLAY 0.659574 (-1665 1285);
PAINT MONO (-1665 1285);
DISPLAY INVISIBLE (-1665 1285);
FORCEPROP 1 LASTPIN (-1675 1275) BN 1
J 2
(-1625 1285);
DISPLAY 0.617021 (-1625 1285);
PAINT PINK (-1625 1285);
FORCEPROP 2 LAST CDS_LIB mstr_standard
J 2
(-1625 1275);
DISPLAY 0.787234 (-1625 1275);
PAINT MONO (-1625 1275);
DISPLAY INVISIBLE (-1625 1275);
FORCEPROP 1 LAST BODY_TYPE PLUMBING
J 2
(-1625 1225);
DISPLAY 1.234043 (-1625 1225);
PAINT GREEN (-1625 1225);
DISPLAY INVISIBLE (-1625 1225);
FORCEPROP 1 LAST HDL_TAP TRUE
J 2
(-1950 1150);
DISPLAY 1.234043 (-1950 1150);
PAINT GREEN (-1950 1150);
DISPLAY INVISIBLE (-1950 1150);
FORCEPROP 1 LAST PATH I109
J 2
(-1625 1275);
DISPLAY 0.936170 (-1625 1275);
PAINT GREEN (-1625 1275);
DISPLAY INVISIBLE (-1625 1275);
FORCEADD TAP..6
R 2
(700 4850);
FORCEPROP 3 LASTPIN (650 4850) SIG_NAME M_G_DQS_DP<15>
J 0
(660 4860);
DISPLAY 0.659574 (660 4860);
PAINT MONO (660 4860);
DISPLAY INVISIBLE (660 4860);
FORCEPROP 1 LASTPIN (650 4850) BN 15
J 2
(700 4860);
DISPLAY 0.617021 (700 4860);
PAINT PINK (700 4860);
FORCEPROP 2 LAST CDS_LIB mstr_standard
J 0
(700 4850);
DISPLAY 0.787234 (700 4850);
PAINT MONO (700 4850);
DISPLAY INVISIBLE (700 4850);
FORCEPROP 1 LAST BODY_TYPE PLUMBING
J 2
(700 4800);
DISPLAY 1.234043 (700 4800);
PAINT GREEN (700 4800);
DISPLAY INVISIBLE (700 4800);
FORCEPROP 1 LAST HDL_TAP TRUE
J 2
(375 4725);
DISPLAY 1.234043 (375 4725);
PAINT GREEN (375 4725);
DISPLAY INVISIBLE (375 4725);
FORCEPROP 1 LAST PATH I11
J 2
(700 4850);
DISPLAY 0.936170 (700 4850);
PAINT GREEN (700 4850);
DISPLAY INVISIBLE (700 4850);
FORCEADD TAP..6
R 2
(-1625 1375);
FORCEPROP 3 LASTPIN (-1675 1375) SIG_NAME M_G_DQ<3>
J 0
(-1665 1385);
DISPLAY 0.659574 (-1665 1385);
PAINT MONO (-1665 1385);
DISPLAY INVISIBLE (-1665 1385);
FORCEPROP 1 LASTPIN (-1675 1375) BN 3
J 2
(-1625 1385);
DISPLAY 0.617021 (-1625 1385);
PAINT PINK (-1625 1385);
FORCEPROP 2 LAST CDS_LIB mstr_standard
J 2
(-1625 1375);
DISPLAY 0.787234 (-1625 1375);
PAINT MONO (-1625 1375);
DISPLAY INVISIBLE (-1625 1375);
FORCEPROP 1 LAST BODY_TYPE PLUMBING
J 2
(-1625 1325);
DISPLAY 1.234043 (-1625 1325);
PAINT GREEN (-1625 1325);
DISPLAY INVISIBLE (-1625 1325);
FORCEPROP 1 LAST HDL_TAP TRUE
J 2
(-1950 1250);
DISPLAY 1.234043 (-1950 1250);
PAINT GREEN (-1950 1250);
DISPLAY INVISIBLE (-1950 1250);
FORCEPROP 1 LAST PATH I110
J 2
(-1625 1375);
DISPLAY 0.936170 (-1625 1375);
PAINT GREEN (-1625 1375);
DISPLAY INVISIBLE (-1625 1375);
FORCEADD SCONN288_H44441004..1
(-2375 2775);
FORCEPROP 1 LAST LOCATION J1G1
J 0
(-2825 4675);
DISPLAY 0.617021 (-2825 4675);
PAINT AQUA (-2825 4675);
FORCEPROP 1 LAST PART_NUMBER H44441-004
J 0
(-2825 775);
DISPLAY 0.617021 (-2825 775);
PAINT BLUE (-2825 775);
FORCEPROP 1 LAST MATERIAL SCONN
J 0
(-2825 4625);
DISPLAY 0.617021 (-2825 4625);
PAINT SKYBLUE (-2825 4625);
FORCEPROP 2 LASTPIN (-2875 1275) $PN 146
J 2
(-2885 1285);
DISPLAY 0.617021 (-2885 1285);
PAINT ORANGE (-2885 1285);
FORCEPROP 2 LASTPIN (-2875 1625) $PN 284
J 2
(-2885 1635);
DISPLAY 0.617021 (-2885 1635);
PAINT ORANGE (-2885 1635);
FORCEPROP 2 LASTPIN (-2875 1425) $PN 285
J 2
(-2885 1435);
DISPLAY 0.617021 (-2885 1435);
PAINT ORANGE (-2885 1435);
FORCEPROP 2 LASTPIN (-2875 1375) $PN 141
J 2
(-2885 1385);
DISPLAY 0.617021 (-2885 1385);
PAINT ORANGE (-2885 1385);
FORCEPROP 2 LASTPIN (-2875 975) $PN 230
J 2
(-2885 985);
DISPLAY 0.617021 (-2885 985);
PAINT ORANGE (-2885 985);
FORCEPROP 2 LASTPIN (-2875 1575) $PN 238
J 2
(-2885 1585);
DISPLAY 0.617021 (-2885 1585);
PAINT ORANGE (-2885 1585);
FORCEPROP 2 LASTPIN (-2875 1525) $PN 140
J 2
(-2885 1535);
DISPLAY 0.617021 (-2885 1535);
PAINT ORANGE (-2885 1535);
FORCEPROP 2 LASTPIN (-2875 1475) $PN 139
J 2
(-2885 1485);
DISPLAY 0.617021 (-2885 1485);
PAINT ORANGE (-2885 1485);
FORCEPROP 2 LASTPIN (-2875 2925) $PN 237
J 2
(-2885 2935);
DISPLAY 0.617021 (-2885 2935);
PAINT ORANGE (-2885 2935);
FORCEPROP 2 LASTPIN (-2875 2875) $PN 93
J 2
(-2885 2885);
DISPLAY 0.617021 (-2885 2885);
PAINT ORANGE (-2885 2885);
FORCEPROP 2 LASTPIN (-2875 2825) $PN 89
J 2
(-2885 2835);
DISPLAY 0.617021 (-2885 2835);
PAINT ORANGE (-2885 2835);
FORCEPROP 2 LASTPIN (-2875 2775) $PN 84
J 2
(-2885 2785);
DISPLAY 0.617021 (-2885 2785);
PAINT ORANGE (-2885 2785);
FORCEPROP 2 LASTPIN (-2875 1175) $PN 144
J 2
(-2885 1185);
DISPLAY 0.617021 (-2885 1185);
PAINT ORANGE (-2885 1185);
FORCEPROP 2 LASTPIN (-2875 1125) $PN 227
J 2
(-2885 1135);
DISPLAY 0.617021 (-2885 1135);
PAINT ORANGE (-2885 1135);
FORCEPROP 2 LASTPIN (-2875 1075) $PN 205
J 2
(-2885 1085);
DISPLAY 0.617021 (-2885 1085);
PAINT ORANGE (-2885 1085);
FORCEPROP 2 LASTPIN (-2875 1875) $PN 58
J 2
(-2885 1885);
DISPLAY 0.617021 (-2885 1885);
PAINT ORANGE (-2885 1885);
FORCEPROP 2 LASTPIN (-2875 1925) $PN 222
J 2
(-2885 1935);
DISPLAY 0.617021 (-2885 1935);
PAINT ORANGE (-2885 1935);
FORCEPROP 2 LASTPIN (-2875 2525) $PN 91
J 2
(-2885 2535);
DISPLAY 0.617021 (-2885 2535);
PAINT ORANGE (-2885 2535);
FORCEPROP 2 LASTPIN (-2875 2475) $PN 87
J 2
(-2885 2485);
DISPLAY 0.617021 (-2885 2485);
PAINT ORANGE (-2885 2485);
FORCEPROP 2 LASTPIN (-2875 1825) $PN 78
J 2
(-2885 1835);
DISPLAY 0.617021 (-2885 1835);
PAINT ORANGE (-2885 1835);
FORCEPROP 2 LASTPIN (-1875 4425) $PN 280
J 0
(-1865 4435);
DISPLAY 0.617021 (-1865 4435);
PAINT ORANGE (-1865 4435);
FORCEPROP 2 LASTPIN (-1875 4375) $PN 135
J 0
(-1865 4385);
DISPLAY 0.617021 (-1865 4385);
PAINT ORANGE (-1865 4385);
FORCEPROP 2 LASTPIN (-1875 4325) $PN 273
J 0
(-1865 4335);
DISPLAY 0.617021 (-1865 4335);
PAINT ORANGE (-1865 4335);
FORCEPROP 2 LASTPIN (-1875 4275) $PN 128
J 0
(-1865 4285);
DISPLAY 0.617021 (-1865 4285);
PAINT ORANGE (-1865 4285);
FORCEPROP 2 LASTPIN (-1875 4225) $PN 282
J 0
(-1865 4235);
DISPLAY 0.617021 (-1865 4235);
PAINT ORANGE (-1865 4235);
FORCEPROP 2 LASTPIN (-1875 4175) $PN 137
J 0
(-1865 4185);
DISPLAY 0.617021 (-1865 4185);
PAINT ORANGE (-1865 4185);
FORCEPROP 2 LASTPIN (-1875 4125) $PN 275
J 0
(-1865 4135);
DISPLAY 0.617021 (-1865 4135);
PAINT ORANGE (-1865 4135);
FORCEPROP 2 LASTPIN (-1875 4075) $PN 130
J 0
(-1865 4085);
DISPLAY 0.617021 (-1865 4085);
PAINT ORANGE (-1865 4085);
FORCEPROP 2 LASTPIN (-1875 4025) $PN 269
J 0
(-1865 4035);
DISPLAY 0.617021 (-1865 4035);
PAINT ORANGE (-1865 4035);
FORCEPROP 2 LASTPIN (-1875 3975) $PN 124
J 0
(-1865 3985);
DISPLAY 0.617021 (-1865 3985);
PAINT ORANGE (-1865 3985);
FORCEPROP 2 LASTPIN (-1875 3925) $PN 262
J 0
(-1865 3935);
DISPLAY 0.617021 (-1865 3935);
PAINT ORANGE (-1865 3935);
FORCEPROP 2 LASTPIN (-1875 3875) $PN 117
J 0
(-1865 3885);
DISPLAY 0.617021 (-1865 3885);
PAINT ORANGE (-1865 3885);
FORCEPROP 2 LASTPIN (-1875 3825) $PN 271
J 0
(-1865 3835);
DISPLAY 0.617021 (-1865 3835);
PAINT ORANGE (-1865 3835);
FORCEPROP 2 LASTPIN (-1875 3775) $PN 126
J 0
(-1865 3785);
DISPLAY 0.617021 (-1865 3785);
PAINT ORANGE (-1865 3785);
FORCEPROP 2 LASTPIN (-1875 3725) $PN 264
J 0
(-1865 3735);
DISPLAY 0.617021 (-1865 3735);
PAINT ORANGE (-1865 3735);
FORCEPROP 2 LASTPIN (-1875 3675) $PN 119
J 0
(-1865 3685);
DISPLAY 0.617021 (-1865 3685);
PAINT ORANGE (-1865 3685);
FORCEPROP 2 LASTPIN (-1875 3625) $PN 258
J 0
(-1865 3635);
DISPLAY 0.617021 (-1865 3635);
PAINT ORANGE (-1865 3635);
FORCEPROP 2 LASTPIN (-1875 3575) $PN 113
J 0
(-1865 3585);
DISPLAY 0.617021 (-1865 3585);
PAINT ORANGE (-1865 3585);
FORCEPROP 2 LASTPIN (-1875 3525) $PN 251
J 0
(-1865 3535);
DISPLAY 0.617021 (-1865 3535);
PAINT ORANGE (-1865 3535);
FORCEPROP 2 LASTPIN (-1875 3475) $PN 106
J 0
(-1865 3485);
DISPLAY 0.617021 (-1865 3485);
PAINT ORANGE (-1865 3485);
FORCEPROP 2 LASTPIN (-1875 3425) $PN 260
J 0
(-1865 3435);
DISPLAY 0.617021 (-1865 3435);
PAINT ORANGE (-1865 3435);
FORCEPROP 2 LASTPIN (-1875 3375) $PN 115
J 0
(-1865 3385);
DISPLAY 0.617021 (-1865 3385);
PAINT ORANGE (-1865 3385);
FORCEPROP 2 LASTPIN (-1875 3325) $PN 253
J 0
(-1865 3335);
DISPLAY 0.617021 (-1865 3335);
PAINT ORANGE (-1865 3335);
FORCEPROP 2 LASTPIN (-1875 3275) $PN 108
J 0
(-1865 3285);
DISPLAY 0.617021 (-1865 3285);
PAINT ORANGE (-1865 3285);
FORCEPROP 2 LASTPIN (-1875 3225) $PN 247
J 0
(-1865 3235);
DISPLAY 0.617021 (-1865 3235);
PAINT ORANGE (-1865 3235);
FORCEPROP 2 LASTPIN (-1875 3175) $PN 102
J 0
(-1865 3185);
DISPLAY 0.617021 (-1865 3185);
PAINT ORANGE (-1865 3185);
FORCEPROP 2 LASTPIN (-1875 3125) $PN 240
J 0
(-1865 3135);
DISPLAY 0.617021 (-1865 3135);
PAINT ORANGE (-1865 3135);
FORCEPROP 2 LASTPIN (-1875 3075) $PN 95
J 0
(-1865 3085);
DISPLAY 0.617021 (-1865 3085);
PAINT ORANGE (-1865 3085);
FORCEPROP 2 LASTPIN (-1875 3025) $PN 249
J 0
(-1865 3035);
DISPLAY 0.617021 (-1865 3035);
PAINT ORANGE (-1865 3035);
FORCEPROP 2 LASTPIN (-1875 2975) $PN 104
J 0
(-1865 2985);
DISPLAY 0.617021 (-1865 2985);
PAINT ORANGE (-1865 2985);
FORCEPROP 2 LASTPIN (-1875 2925) $PN 242
J 0
(-1865 2935);
DISPLAY 0.617021 (-1865 2935);
PAINT ORANGE (-1865 2935);
FORCEPROP 2 LASTPIN (-1875 2875) $PN 97
J 0
(-1865 2885);
DISPLAY 0.617021 (-1865 2885);
PAINT ORANGE (-1865 2885);
FORCEPROP 2 LASTPIN (-1875 2825) $PN 188
J 0
(-1865 2835);
DISPLAY 0.617021 (-1865 2835);
PAINT ORANGE (-1865 2835);
FORCEPROP 2 LASTPIN (-1875 2775) $PN 43
J 0
(-1865 2785);
DISPLAY 0.617021 (-1865 2785);
PAINT ORANGE (-1865 2785);
FORCEPROP 2 LASTPIN (-1875 2725) $PN 181
J 0
(-1865 2735);
DISPLAY 0.617021 (-1865 2735);
PAINT ORANGE (-1865 2735);
FORCEPROP 2 LASTPIN (-1875 2675) $PN 36
J 0
(-1865 2685);
DISPLAY 0.617021 (-1865 2685);
PAINT ORANGE (-1865 2685);
FORCEPROP 2 LASTPIN (-1875 2625) $PN 190
J 0
(-1865 2635);
DISPLAY 0.617021 (-1865 2635);
PAINT ORANGE (-1865 2635);
FORCEPROP 2 LASTPIN (-1875 2575) $PN 45
J 0
(-1865 2585);
DISPLAY 0.617021 (-1865 2585);
PAINT ORANGE (-1865 2585);
FORCEPROP 2 LASTPIN (-1875 2525) $PN 183
J 0
(-1865 2535);
DISPLAY 0.617021 (-1865 2535);
PAINT ORANGE (-1865 2535);
FORCEPROP 2 LASTPIN (-1875 2475) $PN 38
J 0
(-1865 2485);
DISPLAY 0.617021 (-1865 2485);
PAINT ORANGE (-1865 2485);
FORCEPROP 2 LASTPIN (-1875 2425) $PN 177
J 0
(-1865 2435);
DISPLAY 0.617021 (-1865 2435);
PAINT ORANGE (-1865 2435);
FORCEPROP 2 LASTPIN (-1875 2375) $PN 32
J 0
(-1865 2385);
DISPLAY 0.617021 (-1865 2385);
PAINT ORANGE (-1865 2385);
FORCEPROP 2 LASTPIN (-1875 2325) $PN 170
J 0
(-1865 2335);
DISPLAY 0.617021 (-1865 2335);
PAINT ORANGE (-1865 2335);
FORCEPROP 2 LASTPIN (-1875 2275) $PN 25
J 0
(-1865 2285);
DISPLAY 0.617021 (-1865 2285);
PAINT ORANGE (-1865 2285);
FORCEPROP 2 LASTPIN (-1875 2225) $PN 179
J 0
(-1865 2235);
DISPLAY 0.617021 (-1865 2235);
PAINT ORANGE (-1865 2235);
FORCEPROP 2 LASTPIN (-1875 2175) $PN 34
J 0
(-1865 2185);
DISPLAY 0.617021 (-1865 2185);
PAINT ORANGE (-1865 2185);
FORCEPROP 2 LASTPIN (-1875 2125) $PN 172
J 0
(-1865 2135);
DISPLAY 0.617021 (-1865 2135);
PAINT ORANGE (-1865 2135);
FORCEPROP 2 LASTPIN (-1875 2075) $PN 27
J 0
(-1865 2085);
DISPLAY 0.617021 (-1865 2085);
PAINT ORANGE (-1865 2085);
FORCEPROP 2 LASTPIN (-1875 2025) $PN 166
J 0
(-1865 2035);
DISPLAY 0.617021 (-1865 2035);
PAINT ORANGE (-1865 2035);
FORCEPROP 2 LASTPIN (-1875 1975) $PN 21
J 0
(-1865 1985);
DISPLAY 0.617021 (-1865 1985);
PAINT ORANGE (-1865 1985);
FORCEPROP 2 LASTPIN (-1875 1925) $PN 159
J 0
(-1865 1935);
DISPLAY 0.617021 (-1865 1935);
PAINT ORANGE (-1865 1935);
FORCEPROP 2 LASTPIN (-1875 1875) $PN 14
J 0
(-1865 1885);
DISPLAY 0.617021 (-1865 1885);
PAINT ORANGE (-1865 1885);
FORCEPROP 2 LASTPIN (-1875 1825) $PN 168
J 0
(-1865 1835);
DISPLAY 0.617021 (-1865 1835);
PAINT ORANGE (-1865 1835);
FORCEPROP 2 LASTPIN (-1875 1775) $PN 23
J 0
(-1865 1785);
DISPLAY 0.617021 (-1865 1785);
PAINT ORANGE (-1865 1785);
FORCEPROP 2 LASTPIN (-1875 1725) $PN 161
J 0
(-1865 1735);
DISPLAY 0.617021 (-1865 1735);
PAINT ORANGE (-1865 1735);
FORCEPROP 2 LASTPIN (-1875 1675) $PN 16
J 0
(-1865 1685);
DISPLAY 0.617021 (-1865 1685);
PAINT ORANGE (-1865 1685);
FORCEPROP 2 LASTPIN (-1875 1625) $PN 155
J 0
(-1865 1635);
DISPLAY 0.617021 (-1865 1635);
PAINT ORANGE (-1865 1635);
FORCEPROP 2 LASTPIN (-1875 1575) $PN 10
J 0
(-1865 1585);
DISPLAY 0.617021 (-1865 1585);
PAINT ORANGE (-1865 1585);
FORCEPROP 2 LASTPIN (-1875 1525) $PN 148
J 0
(-1865 1535);
DISPLAY 0.617021 (-1865 1535);
PAINT ORANGE (-1865 1535);
FORCEPROP 2 LASTPIN (-1875 1475) $PN 3
J 0
(-1865 1485);
DISPLAY 0.617021 (-1865 1485);
PAINT ORANGE (-1865 1485);
FORCEPROP 2 LASTPIN (-1875 1425) $PN 157
J 0
(-1865 1435);
DISPLAY 0.617021 (-1865 1435);
PAINT ORANGE (-1865 1435);
FORCEPROP 2 LASTPIN (-1875 1375) $PN 12
J 0
(-1865 1385);
DISPLAY 0.617021 (-1865 1385);
PAINT ORANGE (-1865 1385);
FORCEPROP 2 LASTPIN (-1875 1325) $PN 150
J 0
(-1865 1335);
DISPLAY 0.617021 (-1865 1335);
PAINT ORANGE (-1865 1335);
FORCEPROP 2 LASTPIN (-1875 1275) $PN 5
J 0
(-1865 1285);
DISPLAY 0.617021 (-1865 1285);
PAINT ORANGE (-1865 1285);
FORCEPROP 2 LASTPIN (-2875 2675) $PN 203
J 2
(-2885 2685);
DISPLAY 0.617021 (-2885 2685);
PAINT ORANGE (-2885 2685);
FORCEPROP 2 LASTPIN (-2875 2625) $PN 60
J 2
(-2885 2635);
DISPLAY 0.617021 (-2885 2635);
PAINT ORANGE (-2885 2635);
FORCEPROP 2 LASTPIN (-2875 3225) $PN 218
J 2
(-2885 3235);
DISPLAY 0.617021 (-2885 3235);
PAINT ORANGE (-2885 3235);
FORCEPROP 2 LASTPIN (-2875 3175) $PN 219
J 2
(-2885 3185);
DISPLAY 0.617021 (-2885 3185);
PAINT ORANGE (-2885 3185);
FORCEPROP 2 LASTPIN (-2875 3125) $PN 74
J 2
(-2885 3135);
DISPLAY 0.617021 (-2885 3135);
PAINT ORANGE (-2885 3135);
FORCEPROP 2 LASTPIN (-2875 3075) $PN 75
J 2
(-2885 3085);
DISPLAY 0.617021 (-2885 3085);
PAINT ORANGE (-2885 3085);
FORCEPROP 2 LASTPIN (-2875 2375) $PN 199
J 2
(-2885 2385);
DISPLAY 0.617021 (-2885 2385);
PAINT ORANGE (-2885 2385);
FORCEPROP 2 LASTPIN (-2875 2325) $PN 54
J 2
(-2885 2335);
DISPLAY 0.617021 (-2885 2335);
PAINT ORANGE (-2885 2335);
FORCEPROP 2 LASTPIN (-2875 2275) $PN 192
J 2
(-2885 2285);
DISPLAY 0.617021 (-2885 2285);
PAINT ORANGE (-2885 2285);
FORCEPROP 2 LASTPIN (-2875 2225) $PN 47
J 2
(-2885 2235);
DISPLAY 0.617021 (-2885 2235);
PAINT ORANGE (-2885 2235);
FORCEPROP 2 LASTPIN (-2875 2175) $PN 201
J 2
(-2885 2185);
DISPLAY 0.617021 (-2885 2185);
PAINT ORANGE (-2885 2185);
FORCEPROP 2 LASTPIN (-2875 2125) $PN 56
J 2
(-2885 2135);
DISPLAY 0.617021 (-2885 2135);
PAINT ORANGE (-2885 2135);
FORCEPROP 2 LASTPIN (-2875 2075) $PN 194
J 2
(-2885 2085);
DISPLAY 0.617021 (-2885 2085);
PAINT ORANGE (-2885 2085);
FORCEPROP 2 LASTPIN (-2875 2025) $PN 49
J 2
(-2885 2035);
DISPLAY 0.617021 (-2885 2035);
PAINT ORANGE (-2885 2035);
FORCEPROP 2 LASTPIN (-2875 2975) $PN 235
J 2
(-2885 2985);
DISPLAY 0.617021 (-2885 2985);
PAINT ORANGE (-2885 2985);
FORCEPROP 2 LASTPIN (-2875 3375) $PN 207
J 2
(-2885 3385);
DISPLAY 0.617021 (-2885 3385);
PAINT ORANGE (-2885 3385);
FORCEPROP 2 LASTPIN (-2875 3325) $PN 63
J 2
(-2885 3335);
DISPLAY 0.617021 (-2885 3335);
PAINT ORANGE (-2885 3335);
FORCEPROP 2 LASTPIN (-2875 3475) $PN 224
J 2
(-2885 3485);
DISPLAY 0.617021 (-2885 3485);
PAINT ORANGE (-2885 3485);
FORCEPROP 2 LASTPIN (-2875 3425) $PN 81
J 2
(-2885 3435);
DISPLAY 0.617021 (-2885 3435);
PAINT ORANGE (-2885 3435);
FORCEPROP 2 LASTPIN (-2875 1775) $PN 208
J 2
(-2885 1785);
DISPLAY 0.617021 (-2885 1785);
PAINT ORANGE (-2885 1785);
FORCEPROP 2 LASTPIN (-2875 1725) $PN 62
J 2
(-2885 1735);
DISPLAY 0.617021 (-2885 1735);
PAINT ORANGE (-2885 1735);
FORCEPROP 2 LASTPIN (-2875 4425) $PN 234
J 2
(-2885 4435);
DISPLAY 0.617021 (-2885 4435);
PAINT ORANGE (-2885 4435);
FORCEPROP 2 LASTPIN (-2875 4375) $PN 82
J 2
(-2885 4385);
DISPLAY 0.617021 (-2885 4385);
PAINT ORANGE (-2885 4385);
FORCEPROP 2 LASTPIN (-2875 4325) $PN 86
J 2
(-2885 4335);
DISPLAY 0.617021 (-2885 4335);
PAINT ORANGE (-2885 4335);
FORCEPROP 2 LASTPIN (-2875 4275) $PN 228
J 2
(-2885 4285);
DISPLAY 0.617021 (-2885 4285);
PAINT ORANGE (-2885 4285);
FORCEPROP 2 LASTPIN (-2875 4225) $PN 232
J 2
(-2885 4235);
DISPLAY 0.617021 (-2885 4235);
PAINT ORANGE (-2885 4235);
FORCEPROP 2 LASTPIN (-2875 4175) $PN 65
J 2
(-2885 4185);
DISPLAY 0.617021 (-2885 4185);
PAINT ORANGE (-2885 4185);
FORCEPROP 2 LASTPIN (-2875 4125) $PN 210
J 2
(-2885 4135);
DISPLAY 0.617021 (-2885 4135);
PAINT ORANGE (-2885 4135);
FORCEPROP 2 LASTPIN (-2875 4075) $PN 225
J 2
(-2885 4085);
DISPLAY 0.617021 (-2885 4085);
PAINT ORANGE (-2885 4085);
FORCEPROP 2 LASTPIN (-2875 4025) $PN 66
J 2
(-2885 4035);
DISPLAY 0.617021 (-2885 4035);
PAINT ORANGE (-2885 4035);
FORCEPROP 2 LASTPIN (-2875 3975) $PN 68
J 2
(-2885 3985);
DISPLAY 0.617021 (-2885 3985);
PAINT ORANGE (-2885 3985);
FORCEPROP 2 LASTPIN (-2875 3925) $PN 211
J 2
(-2885 3935);
DISPLAY 0.617021 (-2885 3935);
PAINT ORANGE (-2885 3935);
FORCEPROP 2 LASTPIN (-2875 3875) $PN 69
J 2
(-2885 3885);
DISPLAY 0.617021 (-2885 3885);
PAINT ORANGE (-2885 3885);
FORCEPROP 2 LASTPIN (-2875 3825) $PN 213
J 2
(-2885 3835);
DISPLAY 0.617021 (-2885 3835);
PAINT ORANGE (-2885 3835);
FORCEPROP 2 LASTPIN (-2875 3775) $PN 214
J 2
(-2885 3785);
DISPLAY 0.617021 (-2885 3785);
PAINT ORANGE (-2885 3785);
FORCEPROP 2 LASTPIN (-2875 3725) $PN 71
J 2
(-2885 3735);
DISPLAY 0.617021 (-2885 3735);
PAINT ORANGE (-2885 3735);
FORCEPROP 2 LASTPIN (-2875 3675) $PN 216
J 2
(-2885 3685);
DISPLAY 0.617021 (-2885 3685);
PAINT ORANGE (-2885 3685);
FORCEPROP 2 LASTPIN (-2875 3625) $PN 72
J 2
(-2885 3635);
DISPLAY 0.617021 (-2885 3635);
PAINT ORANGE (-2885 3635);
FORCEPROP 2 LASTPIN (-2875 3575) $PN 79
J 2
(-2885 3585);
DISPLAY 0.617021 (-2885 3585);
PAINT ORANGE (-2885 3585);
FORCEPROP 1 LAST PACK_TYPE PIP
J 0
(-2825 4725);
PAINT SKYBLUE (-2825 4725);
DISPLAY INVISIBLE (-2825 4725);
FORCEPROP 2 LAST BOM_COST MEM
J 0
(-2375 2775);
PAINT ORANGE (-2375 2775);
DISPLAY INVISIBLE (-2375 2775);
FORCEPROP 2 LAST CDS_LIB mstr_sconn
J 0
(-2375 2775);
PAINT ORANGE (-2375 2775);
DISPLAY INVISIBLE (-2375 2775);
FORCEPROP 2 LAST SEC_TYPE PIP
J 0
(-2800 4750);
DISPLAY 1.021277 (-2800 4750);
PAINT ORANGE (-2800 4750);
DISPLAY INVISIBLE (-2800 4750);
FORCEPROP 2 LAST SEC 1
J 0
(-2800 4750);
DISPLAY 0.680851 (-2800 4750);
PAINT MONO (-2800 4750);
DISPLAY INVISIBLE (-2800 4750);
FORCEPROP 2 LAST CDS_LOCATION J1G1
J 0
(-2825 4675);
DISPLAY 0.617021 (-2825 4675);
PAINT AQUA (-2825 4675);
DISPLAY INVISIBLE (-2825 4675);
FORCEPROP 1 LAST PATH I111
J 0
(-2375 4625);
PAINT GREEN (-2375 4625);
DISPLAY INVISIBLE (-2375 4625);
FORCEPROP 2 LAST ROOM DDR4_CH_G
J 0
(-2375 2775);
PAINT ORANGE (-2375 2775);
DISPLAY INVISIBLE (-2375 2775);
FORCEADD TAP..6
(-3125 4425);
FORCEPROP 3 LASTPIN (-3075 4425) SIG_NAME M_G_MA<17>
J 0
(-3065 4435);
DISPLAY 0.659574 (-3065 4435);
PAINT MONO (-3065 4435);
DISPLAY INVISIBLE (-3065 4435);
FORCEPROP 1 LASTPIN (-3075 4425) BN 17
J 0
(-3125 4435);
DISPLAY 0.617021 (-3125 4435);
PAINT PINK (-3125 4435);
FORCEPROP 2 LAST CDS_LIB mstr_standard
J 0
(-3125 4425);
DISPLAY 0.787234 (-3125 4425);
PAINT MONO (-3125 4425);
DISPLAY INVISIBLE (-3125 4425);
FORCEPROP 1 LAST BODY_TYPE PLUMBING
J 0
(-3125 4375);
DISPLAY 1.234043 (-3125 4375);
PAINT GREEN (-3125 4375);
DISPLAY INVISIBLE (-3125 4375);
FORCEPROP 1 LAST HDL_TAP TRUE
J 0
(-2800 4300);
DISPLAY 1.234043 (-2800 4300);
PAINT GREEN (-2800 4300);
DISPLAY INVISIBLE (-2800 4300);
FORCEPROP 1 LAST PATH I112
J 0
(-3125 4425);
DISPLAY 0.936170 (-3125 4425);
PAINT GREEN (-3125 4425);
DISPLAY INVISIBLE (-3125 4425);
FORCEADD TAP..6
(-3125 4375);
FORCEPROP 3 LASTPIN (-3075 4375) SIG_NAME M_G_MA<16>
J 0
(-3065 4385);
DISPLAY 0.659574 (-3065 4385);
PAINT MONO (-3065 4385);
DISPLAY INVISIBLE (-3065 4385);
FORCEPROP 1 LASTPIN (-3075 4375) BN 16
J 0
(-3125 4385);
DISPLAY 0.617021 (-3125 4385);
PAINT PINK (-3125 4385);
FORCEPROP 2 LAST CDS_LIB mstr_standard
J 2
(-3125 4375);
DISPLAY 0.787234 (-3125 4375);
PAINT MONO (-3125 4375);
DISPLAY INVISIBLE (-3125 4375);
FORCEPROP 1 LAST BODY_TYPE PLUMBING
J 0
(-3125 4325);
DISPLAY 1.234043 (-3125 4325);
PAINT GREEN (-3125 4325);
DISPLAY INVISIBLE (-3125 4325);
FORCEPROP 1 LAST HDL_TAP TRUE
J 0
(-2800 4250);
DISPLAY 1.234043 (-2800 4250);
PAINT GREEN (-2800 4250);
DISPLAY INVISIBLE (-2800 4250);
FORCEPROP 1 LAST PATH I113
J 0
(-3125 4375);
DISPLAY 0.936170 (-3125 4375);
PAINT GREEN (-3125 4375);
DISPLAY INVISIBLE (-3125 4375);
FORCEADD TAP..6
(-3125 4325);
FORCEPROP 3 LASTPIN (-3075 4325) SIG_NAME M_G_MA<15>
J 0
(-3065 4335);
DISPLAY 0.659574 (-3065 4335);
PAINT MONO (-3065 4335);
DISPLAY INVISIBLE (-3065 4335);
FORCEPROP 1 LASTPIN (-3075 4325) BN 15
J 0
(-3125 4335);
DISPLAY 0.617021 (-3125 4335);
PAINT PINK (-3125 4335);
FORCEPROP 2 LAST CDS_LIB mstr_standard
J 2
(-3125 4325);
DISPLAY 0.787234 (-3125 4325);
PAINT MONO (-3125 4325);
DISPLAY INVISIBLE (-3125 4325);
FORCEPROP 1 LAST BODY_TYPE PLUMBING
J 0
(-3125 4275);
DISPLAY 1.234043 (-3125 4275);
PAINT GREEN (-3125 4275);
DISPLAY INVISIBLE (-3125 4275);
FORCEPROP 1 LAST HDL_TAP TRUE
J 0
(-2800 4200);
DISPLAY 1.234043 (-2800 4200);
PAINT GREEN (-2800 4200);
DISPLAY INVISIBLE (-2800 4200);
FORCEPROP 1 LAST PATH I114
J 0
(-3125 4325);
DISPLAY 0.936170 (-3125 4325);
PAINT GREEN (-3125 4325);
DISPLAY INVISIBLE (-3125 4325);
FORCEADD TAP..6
(-3125 4275);
FORCEPROP 3 LASTPIN (-3075 4275) SIG_NAME M_G_MA<14>
J 0
(-3065 4285);
DISPLAY 0.659574 (-3065 4285);
PAINT MONO (-3065 4285);
DISPLAY INVISIBLE (-3065 4285);
FORCEPROP 1 LASTPIN (-3075 4275) BN 14
J 0
(-3125 4285);
DISPLAY 0.617021 (-3125 4285);
PAINT PINK (-3125 4285);
FORCEPROP 2 LAST CDS_LIB mstr_standard
J 2
(-3125 4275);
DISPLAY 0.787234 (-3125 4275);
PAINT MONO (-3125 4275);
DISPLAY INVISIBLE (-3125 4275);
FORCEPROP 1 LAST BODY_TYPE PLUMBING
J 0
(-3125 4225);
DISPLAY 1.234043 (-3125 4225);
PAINT GREEN (-3125 4225);
DISPLAY INVISIBLE (-3125 4225);
FORCEPROP 1 LAST HDL_TAP TRUE
J 0
(-2800 4150);
DISPLAY 1.234043 (-2800 4150);
PAINT GREEN (-2800 4150);
DISPLAY INVISIBLE (-2800 4150);
FORCEPROP 1 LAST PATH I115
J 0
(-3125 4275);
DISPLAY 0.936170 (-3125 4275);
PAINT GREEN (-3125 4275);
DISPLAY INVISIBLE (-3125 4275);
FORCEADD TAP..6
(-3125 4125);
FORCEPROP 3 LASTPIN (-3075 4125) SIG_NAME M_G_MA<11>
J 0
(-3065 4135);
DISPLAY 0.659574 (-3065 4135);
PAINT MONO (-3065 4135);
DISPLAY INVISIBLE (-3065 4135);
FORCEPROP 1 LASTPIN (-3075 4125) BN 11
J 0
(-3125 4135);
DISPLAY 0.617021 (-3125 4135);
PAINT PINK (-3125 4135);
FORCEPROP 2 LAST CDS_LIB mstr_standard
J 2
(-3125 4125);
DISPLAY 0.787234 (-3125 4125);
PAINT MONO (-3125 4125);
DISPLAY INVISIBLE (-3125 4125);
FORCEPROP 1 LAST BODY_TYPE PLUMBING
J 0
(-3125 4075);
DISPLAY 1.234043 (-3125 4075);
PAINT GREEN (-3125 4075);
DISPLAY INVISIBLE (-3125 4075);
FORCEPROP 1 LAST HDL_TAP TRUE
J 0
(-2800 4000);
DISPLAY 1.234043 (-2800 4000);
PAINT GREEN (-2800 4000);
DISPLAY INVISIBLE (-2800 4000);
FORCEPROP 1 LAST PATH I116
J 0
(-3125 4125);
DISPLAY 0.936170 (-3125 4125);
PAINT GREEN (-3125 4125);
DISPLAY INVISIBLE (-3125 4125);
FORCEADD TAP..6
(-3125 4225);
FORCEPROP 3 LASTPIN (-3075 4225) SIG_NAME M_G_MA<13>
J 0
(-3065 4235);
DISPLAY 0.659574 (-3065 4235);
PAINT MONO (-3065 4235);
DISPLAY INVISIBLE (-3065 4235);
FORCEPROP 1 LASTPIN (-3075 4225) BN 13
J 0
(-3125 4235);
DISPLAY 0.617021 (-3125 4235);
PAINT PINK (-3125 4235);
FORCEPROP 2 LAST CDS_LIB mstr_standard
J 2
(-3125 4225);
DISPLAY 0.787234 (-3125 4225);
PAINT MONO (-3125 4225);
DISPLAY INVISIBLE (-3125 4225);
FORCEPROP 1 LAST BODY_TYPE PLUMBING
J 0
(-3125 4175);
DISPLAY 1.234043 (-3125 4175);
PAINT GREEN (-3125 4175);
DISPLAY INVISIBLE (-3125 4175);
FORCEPROP 1 LAST HDL_TAP TRUE
J 0
(-2800 4100);
DISPLAY 1.234043 (-2800 4100);
PAINT GREEN (-2800 4100);
DISPLAY INVISIBLE (-2800 4100);
FORCEPROP 1 LAST PATH I117
J 0
(-3125 4225);
DISPLAY 0.936170 (-3125 4225);
PAINT GREEN (-3125 4225);
DISPLAY INVISIBLE (-3125 4225);
FORCEADD TAP..6
(-3125 4175);
FORCEPROP 3 LASTPIN (-3075 4175) SIG_NAME M_G_MA<12>
J 0
(-3065 4185);
DISPLAY 0.659574 (-3065 4185);
PAINT MONO (-3065 4185);
DISPLAY INVISIBLE (-3065 4185);
FORCEPROP 1 LASTPIN (-3075 4175) BN 12
J 0
(-3125 4185);
DISPLAY 0.617021 (-3125 4185);
PAINT PINK (-3125 4185);
FORCEPROP 2 LAST CDS_LIB mstr_standard
J 2
(-3125 4175);
DISPLAY 0.787234 (-3125 4175);
PAINT MONO (-3125 4175);
DISPLAY INVISIBLE (-3125 4175);
FORCEPROP 1 LAST BODY_TYPE PLUMBING
J 0
(-3125 4125);
DISPLAY 1.234043 (-3125 4125);
PAINT GREEN (-3125 4125);
DISPLAY INVISIBLE (-3125 4125);
FORCEPROP 1 LAST HDL_TAP TRUE
J 0
(-2800 4050);
DISPLAY 1.234043 (-2800 4050);
PAINT GREEN (-2800 4050);
DISPLAY INVISIBLE (-2800 4050);
FORCEPROP 1 LAST PATH I118
J 0
(-3125 4175);
DISPLAY 0.936170 (-3125 4175);
PAINT GREEN (-3125 4175);
DISPLAY INVISIBLE (-3125 4175);
FORCEADD TAP..6
(-3125 4075);
FORCEPROP 3 LASTPIN (-3075 4075) SIG_NAME M_G_MA<10>
J 0
(-3065 4085);
DISPLAY 0.659574 (-3065 4085);
PAINT MONO (-3065 4085);
DISPLAY INVISIBLE (-3065 4085);
FORCEPROP 1 LASTPIN (-3075 4075) BN 10
J 0
(-3125 4085);
DISPLAY 0.617021 (-3125 4085);
PAINT PINK (-3125 4085);
FORCEPROP 2 LAST CDS_LIB mstr_standard
J 2
(-3125 4075);
DISPLAY 0.787234 (-3125 4075);
PAINT MONO (-3125 4075);
DISPLAY INVISIBLE (-3125 4075);
FORCEPROP 1 LAST BODY_TYPE PLUMBING
J 0
(-3125 4025);
DISPLAY 1.234043 (-3125 4025);
PAINT GREEN (-3125 4025);
DISPLAY INVISIBLE (-3125 4025);
FORCEPROP 1 LAST HDL_TAP TRUE
J 0
(-2800 3950);
DISPLAY 1.234043 (-2800 3950);
PAINT GREEN (-2800 3950);
DISPLAY INVISIBLE (-2800 3950);
FORCEPROP 1 LAST PATH I119
J 0
(-3125 4075);
DISPLAY 0.936170 (-3125 4075);
PAINT GREEN (-3125 4075);
DISPLAY INVISIBLE (-3125 4075);
FORCEADD TAP..6
R 2
(700 4950);
FORCEPROP 3 LASTPIN (650 4950) SIG_NAME M_G_DQS_DP<16>
J 0
(660 4960);
DISPLAY 0.659574 (660 4960);
PAINT MONO (660 4960);
DISPLAY INVISIBLE (660 4960);
FORCEPROP 1 LASTPIN (650 4950) BN 16
J 2
(700 4960);
DISPLAY 0.617021 (700 4960);
PAINT PINK (700 4960);
FORCEPROP 2 LAST CDS_LIB mstr_standard
J 0
(700 4950);
DISPLAY 0.787234 (700 4950);
PAINT MONO (700 4950);
DISPLAY INVISIBLE (700 4950);
FORCEPROP 1 LAST BODY_TYPE PLUMBING
J 2
(700 4900);
DISPLAY 1.234043 (700 4900);
PAINT GREEN (700 4900);
DISPLAY INVISIBLE (700 4900);
FORCEPROP 1 LAST HDL_TAP TRUE
J 2
(375 4825);
DISPLAY 1.234043 (375 4825);
PAINT GREEN (375 4825);
DISPLAY INVISIBLE (375 4825);
FORCEPROP 1 LAST PATH I12
J 2
(700 4950);
DISPLAY 0.936170 (700 4950);
PAINT GREEN (700 4950);
DISPLAY INVISIBLE (700 4950);
FORCEADD TAP..6
(-3125 4025);
FORCEPROP 3 LASTPIN (-3075 4025) SIG_NAME M_G_MA<9>
J 0
(-3065 4035);
DISPLAY 0.659574 (-3065 4035);
PAINT MONO (-3065 4035);
DISPLAY INVISIBLE (-3065 4035);
FORCEPROP 1 LASTPIN (-3075 4025) BN 9
J 0
(-3125 4035);
DISPLAY 0.617021 (-3125 4035);
PAINT PINK (-3125 4035);
FORCEPROP 2 LAST CDS_LIB mstr_standard
J 2
(-3125 4025);
DISPLAY 0.787234 (-3125 4025);
PAINT MONO (-3125 4025);
DISPLAY INVISIBLE (-3125 4025);
FORCEPROP 1 LAST BODY_TYPE PLUMBING
J 0
(-3125 3975);
DISPLAY 1.234043 (-3125 3975);
PAINT GREEN (-3125 3975);
DISPLAY INVISIBLE (-3125 3975);
FORCEPROP 1 LAST HDL_TAP TRUE
J 0
(-2800 3900);
DISPLAY 1.234043 (-2800 3900);
PAINT GREEN (-2800 3900);
DISPLAY INVISIBLE (-2800 3900);
FORCEPROP 1 LAST PATH I120
J 0
(-3125 4025);
DISPLAY 0.936170 (-3125 4025);
PAINT GREEN (-3125 4025);
DISPLAY INVISIBLE (-3125 4025);
FORCEADD TAP..6
(-3125 3875);
FORCEPROP 3 LASTPIN (-3075 3875) SIG_NAME M_G_MA<6>
J 0
(-3065 3885);
DISPLAY 0.659574 (-3065 3885);
PAINT MONO (-3065 3885);
DISPLAY INVISIBLE (-3065 3885);
FORCEPROP 1 LASTPIN (-3075 3875) BN 6
J 0
(-3125 3885);
DISPLAY 0.617021 (-3125 3885);
PAINT PINK (-3125 3885);
FORCEPROP 2 LAST CDS_LIB mstr_standard
J 2
(-3125 3875);
DISPLAY 0.787234 (-3125 3875);
PAINT MONO (-3125 3875);
DISPLAY INVISIBLE (-3125 3875);
FORCEPROP 1 LAST BODY_TYPE PLUMBING
J 0
(-3125 3825);
DISPLAY 1.234043 (-3125 3825);
PAINT GREEN (-3125 3825);
DISPLAY INVISIBLE (-3125 3825);
FORCEPROP 1 LAST HDL_TAP TRUE
J 0
(-2800 3750);
DISPLAY 1.234043 (-2800 3750);
PAINT GREEN (-2800 3750);
DISPLAY INVISIBLE (-2800 3750);
FORCEPROP 1 LAST PATH I121
J 0
(-3125 3875);
DISPLAY 0.936170 (-3125 3875);
PAINT GREEN (-3125 3875);
DISPLAY INVISIBLE (-3125 3875);
FORCEADD TAP..6
(-3125 3975);
FORCEPROP 3 LASTPIN (-3075 3975) SIG_NAME M_G_MA<8>
J 0
(-3065 3985);
DISPLAY 0.659574 (-3065 3985);
PAINT MONO (-3065 3985);
DISPLAY INVISIBLE (-3065 3985);
FORCEPROP 1 LASTPIN (-3075 3975) BN 8
J 0
(-3125 3985);
DISPLAY 0.617021 (-3125 3985);
PAINT PINK (-3125 3985);
FORCEPROP 2 LAST CDS_LIB mstr_standard
J 2
(-3125 3975);
DISPLAY 0.787234 (-3125 3975);
PAINT MONO (-3125 3975);
DISPLAY INVISIBLE (-3125 3975);
FORCEPROP 1 LAST BODY_TYPE PLUMBING
J 0
(-3125 3925);
DISPLAY 1.234043 (-3125 3925);
PAINT GREEN (-3125 3925);
DISPLAY INVISIBLE (-3125 3925);
FORCEPROP 1 LAST HDL_TAP TRUE
J 0
(-2800 3850);
DISPLAY 1.234043 (-2800 3850);
PAINT GREEN (-2800 3850);
DISPLAY INVISIBLE (-2800 3850);
FORCEPROP 1 LAST PATH I122
J 0
(-3125 3975);
DISPLAY 0.936170 (-3125 3975);
PAINT GREEN (-3125 3975);
DISPLAY INVISIBLE (-3125 3975);
FORCEADD TAP..6
(-3125 3925);
FORCEPROP 3 LASTPIN (-3075 3925) SIG_NAME M_G_MA<7>
J 0
(-3065 3935);
DISPLAY 0.659574 (-3065 3935);
PAINT MONO (-3065 3935);
DISPLAY INVISIBLE (-3065 3935);
FORCEPROP 1 LASTPIN (-3075 3925) BN 7
J 0
(-3125 3935);
DISPLAY 0.617021 (-3125 3935);
PAINT PINK (-3125 3935);
FORCEPROP 2 LAST CDS_LIB mstr_standard
J 2
(-3125 3925);
DISPLAY 0.787234 (-3125 3925);
PAINT MONO (-3125 3925);
DISPLAY INVISIBLE (-3125 3925);
FORCEPROP 1 LAST BODY_TYPE PLUMBING
J 0
(-3125 3875);
DISPLAY 1.234043 (-3125 3875);
PAINT GREEN (-3125 3875);
DISPLAY INVISIBLE (-3125 3875);
FORCEPROP 1 LAST HDL_TAP TRUE
J 0
(-2800 3800);
DISPLAY 1.234043 (-2800 3800);
PAINT GREEN (-2800 3800);
DISPLAY INVISIBLE (-2800 3800);
FORCEPROP 1 LAST PATH I123
J 0
(-3125 3925);
DISPLAY 0.936170 (-3125 3925);
PAINT GREEN (-3125 3925);
DISPLAY INVISIBLE (-3125 3925);
FORCEADD TAP..6
(-3125 3825);
FORCEPROP 3 LASTPIN (-3075 3825) SIG_NAME M_G_MA<5>
J 0
(-3065 3835);
DISPLAY 0.659574 (-3065 3835);
PAINT MONO (-3065 3835);
DISPLAY INVISIBLE (-3065 3835);
FORCEPROP 1 LASTPIN (-3075 3825) BN 5
J 0
(-3125 3835);
DISPLAY 0.617021 (-3125 3835);
PAINT PINK (-3125 3835);
FORCEPROP 2 LAST CDS_LIB mstr_standard
J 2
(-3125 3825);
DISPLAY 0.787234 (-3125 3825);
PAINT MONO (-3125 3825);
DISPLAY INVISIBLE (-3125 3825);
FORCEPROP 1 LAST BODY_TYPE PLUMBING
J 0
(-3125 3775);
DISPLAY 1.234043 (-3125 3775);
PAINT GREEN (-3125 3775);
DISPLAY INVISIBLE (-3125 3775);
FORCEPROP 1 LAST HDL_TAP TRUE
J 0
(-2800 3700);
DISPLAY 1.234043 (-2800 3700);
PAINT GREEN (-2800 3700);
DISPLAY INVISIBLE (-2800 3700);
FORCEPROP 1 LAST PATH I124
J 0
(-3125 3825);
DISPLAY 0.936170 (-3125 3825);
PAINT GREEN (-3125 3825);
DISPLAY INVISIBLE (-3125 3825);
FORCEADD TAP..6
(-3125 3775);
FORCEPROP 3 LASTPIN (-3075 3775) SIG_NAME M_G_MA<4>
J 0
(-3065 3785);
DISPLAY 0.659574 (-3065 3785);
PAINT MONO (-3065 3785);
DISPLAY INVISIBLE (-3065 3785);
FORCEPROP 1 LASTPIN (-3075 3775) BN 4
J 0
(-3125 3785);
DISPLAY 0.617021 (-3125 3785);
PAINT PINK (-3125 3785);
FORCEPROP 2 LAST CDS_LIB mstr_standard
J 2
(-3125 3775);
DISPLAY 0.787234 (-3125 3775);
PAINT MONO (-3125 3775);
DISPLAY INVISIBLE (-3125 3775);
FORCEPROP 1 LAST BODY_TYPE PLUMBING
J 0
(-3125 3725);
DISPLAY 1.234043 (-3125 3725);
PAINT GREEN (-3125 3725);
DISPLAY INVISIBLE (-3125 3725);
FORCEPROP 1 LAST HDL_TAP TRUE
J 0
(-2800 3650);
DISPLAY 1.234043 (-2800 3650);
PAINT GREEN (-2800 3650);
DISPLAY INVISIBLE (-2800 3650);
FORCEPROP 1 LAST PATH I125
J 0
(-3125 3775);
DISPLAY 0.936170 (-3125 3775);
PAINT GREEN (-3125 3775);
DISPLAY INVISIBLE (-3125 3775);
FORCEADD TAP..6
(-3125 3725);
FORCEPROP 3 LASTPIN (-3075 3725) SIG_NAME M_G_MA<3>
J 0
(-3065 3735);
DISPLAY 0.659574 (-3065 3735);
PAINT MONO (-3065 3735);
DISPLAY INVISIBLE (-3065 3735);
FORCEPROP 1 LASTPIN (-3075 3725) BN 3
J 0
(-3125 3735);
DISPLAY 0.617021 (-3125 3735);
PAINT PINK (-3125 3735);
FORCEPROP 2 LAST CDS_LIB mstr_standard
J 2
(-3125 3725);
DISPLAY 0.787234 (-3125 3725);
PAINT MONO (-3125 3725);
DISPLAY INVISIBLE (-3125 3725);
FORCEPROP 1 LAST BODY_TYPE PLUMBING
J 0
(-3125 3675);
DISPLAY 1.234043 (-3125 3675);
PAINT GREEN (-3125 3675);
DISPLAY INVISIBLE (-3125 3675);
FORCEPROP 1 LAST HDL_TAP TRUE
J 0
(-2800 3600);
DISPLAY 1.234043 (-2800 3600);
PAINT GREEN (-2800 3600);
DISPLAY INVISIBLE (-2800 3600);
FORCEPROP 1 LAST PATH I126
J 0
(-3125 3725);
DISPLAY 0.936170 (-3125 3725);
PAINT GREEN (-3125 3725);
DISPLAY INVISIBLE (-3125 3725);
FORCEADD TAP..6
(-3125 3675);
FORCEPROP 3 LASTPIN (-3075 3675) SIG_NAME M_G_MA<2>
J 0
(-3065 3685);
DISPLAY 0.659574 (-3065 3685);
PAINT MONO (-3065 3685);
DISPLAY INVISIBLE (-3065 3685);
FORCEPROP 1 LASTPIN (-3075 3675) BN 2
J 0
(-3125 3685);
DISPLAY 0.617021 (-3125 3685);
PAINT PINK (-3125 3685);
FORCEPROP 2 LAST CDS_LIB mstr_standard
J 2
(-3125 3675);
DISPLAY 0.787234 (-3125 3675);
PAINT MONO (-3125 3675);
DISPLAY INVISIBLE (-3125 3675);
FORCEPROP 1 LAST BODY_TYPE PLUMBING
J 0
(-3125 3625);
DISPLAY 1.234043 (-3125 3625);
PAINT GREEN (-3125 3625);
DISPLAY INVISIBLE (-3125 3625);
FORCEPROP 1 LAST HDL_TAP TRUE
J 0
(-2800 3550);
DISPLAY 1.234043 (-2800 3550);
PAINT GREEN (-2800 3550);
DISPLAY INVISIBLE (-2800 3550);
FORCEPROP 1 LAST PATH I127
J 0
(-3125 3675);
DISPLAY 0.936170 (-3125 3675);
PAINT GREEN (-3125 3675);
DISPLAY INVISIBLE (-3125 3675);
FORCEADD TAP..6
(-3125 3625);
FORCEPROP 3 LASTPIN (-3075 3625) SIG_NAME M_G_MA<1>
J 0
(-3065 3635);
DISPLAY 0.659574 (-3065 3635);
PAINT MONO (-3065 3635);
DISPLAY INVISIBLE (-3065 3635);
FORCEPROP 1 LASTPIN (-3075 3625) BN 1
J 0
(-3125 3635);
DISPLAY 0.617021 (-3125 3635);
PAINT PINK (-3125 3635);
FORCEPROP 2 LAST CDS_LIB mstr_standard
J 2
(-3125 3625);
DISPLAY 0.787234 (-3125 3625);
PAINT MONO (-3125 3625);
DISPLAY INVISIBLE (-3125 3625);
FORCEPROP 1 LAST BODY_TYPE PLUMBING
J 0
(-3125 3575);
DISPLAY 1.234043 (-3125 3575);
PAINT GREEN (-3125 3575);
DISPLAY INVISIBLE (-3125 3575);
FORCEPROP 1 LAST HDL_TAP TRUE
J 0
(-2800 3500);
DISPLAY 1.234043 (-2800 3500);
PAINT GREEN (-2800 3500);
DISPLAY INVISIBLE (-2800 3500);
FORCEPROP 1 LAST PATH I128
J 0
(-3125 3625);
DISPLAY 0.936170 (-3125 3625);
PAINT GREEN (-3125 3625);
DISPLAY INVISIBLE (-3125 3625);
FORCEADD TAP..6
(-3125 3575);
FORCEPROP 3 LASTPIN (-3075 3575) SIG_NAME M_G_MA<0>
J 0
(-3065 3585);
DISPLAY 0.659574 (-3065 3585);
PAINT MONO (-3065 3585);
DISPLAY INVISIBLE (-3065 3585);
FORCEPROP 1 LASTPIN (-3075 3575) BN 0
J 0
(-3125 3585);
DISPLAY 0.617021 (-3125 3585);
PAINT PINK (-3125 3585);
FORCEPROP 2 LAST CDS_LIB mstr_standard
J 2
(-3125 3575);
DISPLAY 0.787234 (-3125 3575);
PAINT MONO (-3125 3575);
DISPLAY INVISIBLE (-3125 3575);
FORCEPROP 1 LAST BODY_TYPE PLUMBING
J 0
(-3125 3525);
DISPLAY 1.234043 (-3125 3525);
PAINT GREEN (-3125 3525);
DISPLAY INVISIBLE (-3125 3525);
FORCEPROP 1 LAST HDL_TAP TRUE
J 0
(-2800 3450);
DISPLAY 1.234043 (-2800 3450);
PAINT GREEN (-2800 3450);
DISPLAY INVISIBLE (-2800 3450);
FORCEPROP 1 LAST PATH I129
J 0
(-3125 3575);
DISPLAY 0.936170 (-3125 3575);
PAINT GREEN (-3125 3575);
DISPLAY INVISIBLE (-3125 3575);
FORCEADD TAP..6
R 2
(700 4450);
FORCEPROP 3 LASTPIN (650 4450) SIG_NAME M_G_DQS_DP<11>
J 0
(660 4460);
DISPLAY 0.659574 (660 4460);
PAINT MONO (660 4460);
DISPLAY INVISIBLE (660 4460);
FORCEPROP 1 LASTPIN (650 4450) BN 11
J 2
(700 4460);
DISPLAY 0.617021 (700 4460);
PAINT PINK (700 4460);
FORCEPROP 2 LAST CDS_LIB mstr_standard
J 0
(700 4450);
DISPLAY 0.787234 (700 4450);
PAINT MONO (700 4450);
DISPLAY INVISIBLE (700 4450);
FORCEPROP 1 LAST BODY_TYPE PLUMBING
J 2
(700 4400);
DISPLAY 1.234043 (700 4400);
PAINT GREEN (700 4400);
DISPLAY INVISIBLE (700 4400);
FORCEPROP 1 LAST HDL_TAP TRUE
J 2
(375 4325);
DISPLAY 1.234043 (375 4325);
PAINT GREEN (375 4325);
DISPLAY INVISIBLE (375 4325);
FORCEPROP 1 LAST PATH I13
J 2
(700 4450);
DISPLAY 0.936170 (700 4450);
PAINT GREEN (700 4450);
DISPLAY INVISIBLE (700 4450);
FORCEADD TAP..6
(-3125 3475);
FORCEPROP 3 LASTPIN (-3075 3475) SIG_NAME M_G_BA<1>
J 0
(-3065 3485);
DISPLAY 0.659574 (-3065 3485);
PAINT MONO (-3065 3485);
DISPLAY INVISIBLE (-3065 3485);
FORCEPROP 1 LASTPIN (-3075 3475) BN 1
J 0
(-3125 3485);
DISPLAY 0.617021 (-3125 3485);
PAINT PINK (-3125 3485);
FORCEPROP 2 LAST CDS_LIB mstr_standard
J 0
(-3125 3475);
DISPLAY 0.787234 (-3125 3475);
PAINT MONO (-3125 3475);
DISPLAY INVISIBLE (-3125 3475);
FORCEPROP 1 LAST BODY_TYPE PLUMBING
J 0
(-3125 3425);
DISPLAY 1.234043 (-3125 3425);
PAINT GREEN (-3125 3425);
DISPLAY INVISIBLE (-3125 3425);
FORCEPROP 1 LAST HDL_TAP TRUE
J 0
(-2800 3350);
DISPLAY 1.234043 (-2800 3350);
PAINT GREEN (-2800 3350);
DISPLAY INVISIBLE (-2800 3350);
FORCEPROP 1 LAST PATH I130
J 0
(-3125 3475);
DISPLAY 0.936170 (-3125 3475);
PAINT GREEN (-3125 3475);
DISPLAY INVISIBLE (-3125 3475);
FORCEADD OFFPAGE..1
(-3775 4475);
FORCEPROP 2 LAST $XR0 57 
J 0
(-3996 4475);
DISPLAY 0.638298 (-3996 4475);
PAINT MONO (-3996 4475);
FORCEPROP 2 LAST $XR1 78 
J 0
(-4086 4475);
DISPLAY 0.638298 (-4086 4475);
PAINT MONO (-4086 4475);
FORCEPROP 2 LAST CDS_LIB mstr_standard
J 0
(-3775 4475);
DISPLAY 0.787234 (-3775 4475);
PAINT MONO (-3775 4475);
DISPLAY INVISIBLE (-3775 4475);
FORCEPROP 1 LAST OFFPAGE TRUE
J 0
(-3450 4350);
DISPLAY 0.936170 (-3450 4350);
PAINT GREEN (-3450 4350);
DISPLAY INVISIBLE (-3450 4350);
FORCEPROP 1 LAST COMMENT_BODY TRUE
J 0
(-3650 4375);
DISPLAY 0.936170 (-3650 4375);
PAINT GREEN (-3650 4375);
DISPLAY INVISIBLE (-3650 4375);
FORCEPROP 2 LAST PATH I131
J 0
(-3725 4550);
DISPLAY 0.787234 (-3725 4550);
PAINT MONO (-3725 4550);
DISPLAY INVISIBLE (-3725 4550);
FORCEADD OFFPAGE..1
(-3775 3550);
FORCEPROP 2 LAST $XR0 57 
J 0
(-3996 3550);
DISPLAY 0.638298 (-3996 3550);
PAINT MONO (-3996 3550);
FORCEPROP 2 LAST $XR1 78 
J 0
(-4086 3550);
DISPLAY 0.638298 (-4086 3550);
PAINT MONO (-4086 3550);
FORCEPROP 2 LAST CDS_LIB mstr_standard
J 0
(-3775 3550);
DISPLAY 0.787234 (-3775 3550);
PAINT MONO (-3775 3550);
DISPLAY INVISIBLE (-3775 3550);
FORCEPROP 1 LAST OFFPAGE TRUE
J 0
(-3450 3425);
DISPLAY 0.936170 (-3450 3425);
PAINT GREEN (-3450 3425);
DISPLAY INVISIBLE (-3450 3425);
FORCEPROP 1 LAST COMMENT_BODY TRUE
J 0
(-3650 3450);
DISPLAY 0.936170 (-3650 3450);
PAINT GREEN (-3650 3450);
DISPLAY INVISIBLE (-3650 3450);
FORCEPROP 2 LAST PATH I132
J 0
(-3725 3625);
DISPLAY 0.787234 (-3725 3625);
PAINT MONO (-3725 3625);
DISPLAY INVISIBLE (-3725 3625);
FORCEADD TAP..6
(-3125 3425);
FORCEPROP 3 LASTPIN (-3075 3425) SIG_NAME M_G_BA<0>
J 0
(-3065 3435);
DISPLAY 0.659574 (-3065 3435);
PAINT MONO (-3065 3435);
DISPLAY INVISIBLE (-3065 3435);
FORCEPROP 1 LASTPIN (-3075 3425) BN 0
J 0
(-3125 3435);
DISPLAY 0.617021 (-3125 3435);
PAINT PINK (-3125 3435);
FORCEPROP 2 LAST CDS_LIB mstr_standard
J 0
(-3125 3425);
DISPLAY 0.787234 (-3125 3425);
PAINT MONO (-3125 3425);
DISPLAY INVISIBLE (-3125 3425);
FORCEPROP 1 LAST BODY_TYPE PLUMBING
J 0
(-3125 3375);
DISPLAY 1.234043 (-3125 3375);
PAINT GREEN (-3125 3375);
DISPLAY INVISIBLE (-3125 3375);
FORCEPROP 1 LAST HDL_TAP TRUE
J 0
(-2800 3300);
DISPLAY 1.234043 (-2800 3300);
PAINT GREEN (-2800 3300);
DISPLAY INVISIBLE (-2800 3300);
FORCEPROP 1 LAST PATH I133
J 0
(-3125 3425);
DISPLAY 0.936170 (-3125 3425);
PAINT GREEN (-3125 3425);
DISPLAY INVISIBLE (-3125 3425);
FORCEADD TAP..6
(-3125 3375);
FORCEPROP 3 LASTPIN (-3075 3375) SIG_NAME M_G_BG<1>
J 0
(-3065 3385);
DISPLAY 0.659574 (-3065 3385);
PAINT MONO (-3065 3385);
DISPLAY INVISIBLE (-3065 3385);
FORCEPROP 1 LASTPIN (-3075 3375) BN 1
J 0
(-3125 3385);
DISPLAY 0.617021 (-3125 3385);
PAINT PINK (-3125 3385);
FORCEPROP 2 LAST CDS_LIB mstr_standard
J 0
(-3125 3375);
DISPLAY 0.787234 (-3125 3375);
PAINT MONO (-3125 3375);
DISPLAY INVISIBLE (-3125 3375);
FORCEPROP 1 LAST BODY_TYPE PLUMBING
J 0
(-3125 3325);
DISPLAY 1.234043 (-3125 3325);
PAINT GREEN (-3125 3325);
DISPLAY INVISIBLE (-3125 3325);
FORCEPROP 1 LAST HDL_TAP TRUE
J 0
(-2800 3250);
DISPLAY 1.234043 (-2800 3250);
PAINT GREEN (-2800 3250);
DISPLAY INVISIBLE (-2800 3250);
FORCEPROP 1 LAST PATH I134
J 0
(-3125 3375);
DISPLAY 0.936170 (-3125 3375);
PAINT GREEN (-3125 3375);
DISPLAY INVISIBLE (-3125 3375);
FORCEADD TAP..6
(-3125 3325);
FORCEPROP 3 LASTPIN (-3075 3325) SIG_NAME M_G_BG<0>
J 0
(-3065 3335);
DISPLAY 0.659574 (-3065 3335);
PAINT MONO (-3065 3335);
DISPLAY INVISIBLE (-3065 3335);
FORCEPROP 1 LASTPIN (-3075 3325) BN 0
J 0
(-3125 3335);
DISPLAY 0.617021 (-3125 3335);
PAINT PINK (-3125 3335);
FORCEPROP 2 LAST CDS_LIB mstr_standard
J 0
(-3125 3325);
DISPLAY 0.787234 (-3125 3325);
PAINT MONO (-3125 3325);
DISPLAY INVISIBLE (-3125 3325);
FORCEPROP 1 LAST BODY_TYPE PLUMBING
J 0
(-3125 3275);
DISPLAY 1.234043 (-3125 3275);
PAINT GREEN (-3125 3275);
DISPLAY INVISIBLE (-3125 3275);
FORCEPROP 1 LAST HDL_TAP TRUE
J 0
(-2800 3200);
DISPLAY 1.234043 (-2800 3200);
PAINT GREEN (-2800 3200);
DISPLAY INVISIBLE (-2800 3200);
FORCEPROP 1 LAST PATH I135
J 0
(-3125 3325);
DISPLAY 0.936170 (-3125 3325);
PAINT GREEN (-3125 3325);
DISPLAY INVISIBLE (-3125 3325);
FORCEADD OFFPAGE..1
(-3775 3025);
FORCEPROP 2 LAST $XR0 57 
J 0
(-3996 3025);
DISPLAY 0.638298 (-3996 3025);
PAINT MONO (-3996 3025);
FORCEPROP 2 LAST $XR1 78 
J 0
(-4086 3025);
DISPLAY 0.638298 (-4086 3025);
PAINT MONO (-4086 3025);
FORCEPROP 2 LAST CDS_LIB mstr_standard
J 0
(-3775 3025);
DISPLAY 0.787234 (-3775 3025);
PAINT MONO (-3775 3025);
DISPLAY INVISIBLE (-3775 3025);
FORCEPROP 1 LAST OFFPAGE TRUE
J 0
(-3450 2900);
DISPLAY 0.936170 (-3450 2900);
PAINT GREEN (-3450 2900);
DISPLAY INVISIBLE (-3450 2900);
FORCEPROP 1 LAST COMMENT_BODY TRUE
J 0
(-3650 2925);
DISPLAY 0.936170 (-3650 2925);
PAINT GREEN (-3650 2925);
DISPLAY INVISIBLE (-3650 2925);
FORCEPROP 2 LAST PATH I136
J 0
(-3725 3100);
DISPLAY 0.787234 (-3725 3100);
PAINT MONO (-3725 3100);
DISPLAY INVISIBLE (-3725 3100);
FORCEADD OFFPAGE..1
(-3775 3425);
FORCEPROP 2 LAST $XR0 57 
J 0
(-3996 3425);
DISPLAY 0.638298 (-3996 3425);
PAINT MONO (-3996 3425);
FORCEPROP 2 LAST $XR1 78 
J 0
(-4086 3425);
DISPLAY 0.638298 (-4086 3425);
PAINT MONO (-4086 3425);
FORCEPROP 2 LAST CDS_LIB mstr_standard
J 0
(-3775 3425);
DISPLAY 0.787234 (-3775 3425);
PAINT MONO (-3775 3425);
DISPLAY INVISIBLE (-3775 3425);
FORCEPROP 1 LAST OFFPAGE TRUE
J 0
(-3450 3300);
DISPLAY 0.936170 (-3450 3300);
PAINT GREEN (-3450 3300);
DISPLAY INVISIBLE (-3450 3300);
FORCEPROP 1 LAST COMMENT_BODY TRUE
J 0
(-3650 3325);
DISPLAY 0.936170 (-3650 3325);
PAINT GREEN (-3650 3325);
DISPLAY INVISIBLE (-3650 3325);
FORCEPROP 2 LAST PATH I137
J 0
(-3725 3500);
DISPLAY 0.787234 (-3725 3500);
PAINT MONO (-3725 3500);
DISPLAY INVISIBLE (-3725 3500);
FORCEADD TAP..6
(-3125 2375);
FORCEPROP 3 LASTPIN (-3075 2375) SIG_NAME M_G_ECC<6>
J 0
(-3065 2385);
DISPLAY 0.659574 (-3065 2385);
PAINT MONO (-3065 2385);
DISPLAY INVISIBLE (-3065 2385);
FORCEPROP 1 LASTPIN (-3075 2375) BN 6
J 0
(-3125 2385);
DISPLAY 0.617021 (-3125 2385);
PAINT PINK (-3125 2385);
FORCEPROP 2 LAST CDS_LIB mstr_standard
J 0
(-3125 2375);
DISPLAY 0.787234 (-3125 2375);
PAINT MONO (-3125 2375);
DISPLAY INVISIBLE (-3125 2375);
FORCEPROP 1 LAST BODY_TYPE PLUMBING
J 0
(-3125 2325);
DISPLAY 1.234043 (-3125 2325);
PAINT GREEN (-3125 2325);
DISPLAY INVISIBLE (-3125 2325);
FORCEPROP 1 LAST HDL_TAP TRUE
J 0
(-2800 2250);
DISPLAY 1.234043 (-2800 2250);
PAINT GREEN (-2800 2250);
DISPLAY INVISIBLE (-2800 2250);
FORCEPROP 1 LAST PATH I138
J 0
(-3125 2375);
DISPLAY 0.936170 (-3125 2375);
PAINT GREEN (-3125 2375);
DISPLAY INVISIBLE (-3125 2375);
FORCEADD TAP..6
(-3125 2325);
FORCEPROP 3 LASTPIN (-3075 2325) SIG_NAME M_G_ECC<7>
J 0
(-3065 2335);
DISPLAY 0.659574 (-3065 2335);
PAINT MONO (-3065 2335);
DISPLAY INVISIBLE (-3065 2335);
FORCEPROP 1 LASTPIN (-3075 2325) BN 7
J 0
(-3125 2335);
DISPLAY 0.617021 (-3125 2335);
PAINT PINK (-3125 2335);
FORCEPROP 2 LAST CDS_LIB mstr_standard
J 0
(-3125 2325);
DISPLAY 0.787234 (-3125 2325);
PAINT MONO (-3125 2325);
DISPLAY INVISIBLE (-3125 2325);
FORCEPROP 1 LAST BODY_TYPE PLUMBING
J 0
(-3125 2275);
DISPLAY 1.234043 (-3125 2275);
PAINT GREEN (-3125 2275);
DISPLAY INVISIBLE (-3125 2275);
FORCEPROP 1 LAST HDL_TAP TRUE
J 0
(-2800 2200);
DISPLAY 1.234043 (-2800 2200);
PAINT GREEN (-2800 2200);
DISPLAY INVISIBLE (-2800 2200);
FORCEPROP 1 LAST PATH I139
J 0
(-3125 2325);
DISPLAY 0.936170 (-3125 2325);
PAINT GREEN (-3125 2325);
DISPLAY INVISIBLE (-3125 2325);
FORCEADD TAP..6
R 2
(700 4550);
FORCEPROP 3 LASTPIN (650 4550) SIG_NAME M_G_DQS_DP<12>
J 0
(660 4560);
DISPLAY 0.659574 (660 4560);
PAINT MONO (660 4560);
DISPLAY INVISIBLE (660 4560);
FORCEPROP 1 LASTPIN (650 4550) BN 12
J 2
(700 4560);
DISPLAY 0.617021 (700 4560);
PAINT PINK (700 4560);
FORCEPROP 2 LAST CDS_LIB mstr_standard
J 0
(700 4550);
DISPLAY 0.787234 (700 4550);
PAINT MONO (700 4550);
DISPLAY INVISIBLE (700 4550);
FORCEPROP 1 LAST BODY_TYPE PLUMBING
J 2
(700 4500);
DISPLAY 1.234043 (700 4500);
PAINT GREEN (700 4500);
DISPLAY INVISIBLE (700 4500);
FORCEPROP 1 LAST HDL_TAP TRUE
J 2
(375 4425);
DISPLAY 1.234043 (375 4425);
PAINT GREEN (375 4425);
DISPLAY INVISIBLE (375 4425);
FORCEPROP 1 LAST PATH I14
J 2
(700 4550);
DISPLAY 0.936170 (700 4550);
PAINT GREEN (700 4550);
DISPLAY INVISIBLE (700 4550);
FORCEADD TAP..6
(-3125 2275);
FORCEPROP 3 LASTPIN (-3075 2275) SIG_NAME M_G_ECC<4>
J 0
(-3065 2285);
DISPLAY 0.659574 (-3065 2285);
PAINT MONO (-3065 2285);
DISPLAY INVISIBLE (-3065 2285);
FORCEPROP 1 LASTPIN (-3075 2275) BN 4
J 0
(-3125 2285);
DISPLAY 0.617021 (-3125 2285);
PAINT PINK (-3125 2285);
FORCEPROP 2 LAST CDS_LIB mstr_standard
J 0
(-3125 2275);
DISPLAY 0.787234 (-3125 2275);
PAINT MONO (-3125 2275);
DISPLAY INVISIBLE (-3125 2275);
FORCEPROP 1 LAST BODY_TYPE PLUMBING
J 0
(-3125 2225);
DISPLAY 1.234043 (-3125 2225);
PAINT GREEN (-3125 2225);
DISPLAY INVISIBLE (-3125 2225);
FORCEPROP 1 LAST HDL_TAP TRUE
J 0
(-2800 2150);
DISPLAY 1.234043 (-2800 2150);
PAINT GREEN (-2800 2150);
DISPLAY INVISIBLE (-2800 2150);
FORCEPROP 1 LAST PATH I140
J 0
(-3125 2275);
DISPLAY 0.936170 (-3125 2275);
PAINT GREEN (-3125 2275);
DISPLAY INVISIBLE (-3125 2275);
FORCEADD TAP..6
(-3125 2225);
FORCEPROP 3 LASTPIN (-3075 2225) SIG_NAME M_G_ECC<5>
J 0
(-3065 2235);
DISPLAY 0.659574 (-3065 2235);
PAINT MONO (-3065 2235);
DISPLAY INVISIBLE (-3065 2235);
FORCEPROP 1 LASTPIN (-3075 2225) BN 5
J 0
(-3125 2235);
DISPLAY 0.617021 (-3125 2235);
PAINT PINK (-3125 2235);
FORCEPROP 2 LAST CDS_LIB mstr_standard
J 0
(-3125 2225);
DISPLAY 0.787234 (-3125 2225);
PAINT MONO (-3125 2225);
DISPLAY INVISIBLE (-3125 2225);
FORCEPROP 1 LAST BODY_TYPE PLUMBING
J 0
(-3125 2175);
DISPLAY 1.234043 (-3125 2175);
PAINT GREEN (-3125 2175);
DISPLAY INVISIBLE (-3125 2175);
FORCEPROP 1 LAST HDL_TAP TRUE
J 0
(-2800 2100);
DISPLAY 1.234043 (-2800 2100);
PAINT GREEN (-2800 2100);
DISPLAY INVISIBLE (-2800 2100);
FORCEPROP 1 LAST PATH I141
J 0
(-3125 2225);
DISPLAY 0.936170 (-3125 2225);
PAINT GREEN (-3125 2225);
DISPLAY INVISIBLE (-3125 2225);
FORCEADD TAP..6
(-3125 2075);
FORCEPROP 3 LASTPIN (-3075 2075) SIG_NAME M_G_ECC<0>
J 0
(-3065 2085);
DISPLAY 0.659574 (-3065 2085);
PAINT MONO (-3065 2085);
DISPLAY INVISIBLE (-3065 2085);
FORCEPROP 1 LASTPIN (-3075 2075) BN 0
J 0
(-3125 2085);
DISPLAY 0.617021 (-3125 2085);
PAINT PINK (-3125 2085);
FORCEPROP 2 LAST CDS_LIB mstr_standard
J 0
(-3125 2075);
DISPLAY 0.787234 (-3125 2075);
PAINT MONO (-3125 2075);
DISPLAY INVISIBLE (-3125 2075);
FORCEPROP 1 LAST BODY_TYPE PLUMBING
J 0
(-3125 2025);
DISPLAY 1.234043 (-3125 2025);
PAINT GREEN (-3125 2025);
DISPLAY INVISIBLE (-3125 2025);
FORCEPROP 1 LAST HDL_TAP TRUE
J 0
(-2800 1950);
DISPLAY 1.234043 (-2800 1950);
PAINT GREEN (-2800 1950);
DISPLAY INVISIBLE (-2800 1950);
FORCEPROP 1 LAST PATH I142
J 0
(-3125 2075);
DISPLAY 0.936170 (-3125 2075);
PAINT GREEN (-3125 2075);
DISPLAY INVISIBLE (-3125 2075);
FORCEADD TAP..6
(-3125 2125);
FORCEPROP 3 LASTPIN (-3075 2125) SIG_NAME M_G_ECC<3>
J 0
(-3065 2135);
DISPLAY 0.659574 (-3065 2135);
PAINT MONO (-3065 2135);
DISPLAY INVISIBLE (-3065 2135);
FORCEPROP 1 LASTPIN (-3075 2125) BN 3
J 0
(-3125 2135);
DISPLAY 0.617021 (-3125 2135);
PAINT PINK (-3125 2135);
FORCEPROP 2 LAST CDS_LIB mstr_standard
J 0
(-3125 2125);
DISPLAY 0.787234 (-3125 2125);
PAINT MONO (-3125 2125);
DISPLAY INVISIBLE (-3125 2125);
FORCEPROP 1 LAST BODY_TYPE PLUMBING
J 0
(-3125 2075);
DISPLAY 1.234043 (-3125 2075);
PAINT GREEN (-3125 2075);
DISPLAY INVISIBLE (-3125 2075);
FORCEPROP 1 LAST HDL_TAP TRUE
J 0
(-2800 2000);
DISPLAY 1.234043 (-2800 2000);
PAINT GREEN (-2800 2000);
DISPLAY INVISIBLE (-2800 2000);
FORCEPROP 1 LAST PATH I143
J 0
(-3125 2125);
DISPLAY 0.936170 (-3125 2125);
PAINT GREEN (-3125 2125);
DISPLAY INVISIBLE (-3125 2125);
FORCEADD TAP..6
(-3125 2175);
FORCEPROP 3 LASTPIN (-3075 2175) SIG_NAME M_G_ECC<2>
J 0
(-3065 2185);
DISPLAY 0.659574 (-3065 2185);
PAINT MONO (-3065 2185);
DISPLAY INVISIBLE (-3065 2185);
FORCEPROP 1 LASTPIN (-3075 2175) BN 2
J 0
(-3125 2185);
DISPLAY 0.617021 (-3125 2185);
PAINT PINK (-3125 2185);
FORCEPROP 2 LAST CDS_LIB mstr_standard
J 0
(-3125 2175);
DISPLAY 0.787234 (-3125 2175);
PAINT MONO (-3125 2175);
DISPLAY INVISIBLE (-3125 2175);
FORCEPROP 1 LAST BODY_TYPE PLUMBING
J 0
(-3125 2125);
DISPLAY 1.234043 (-3125 2125);
PAINT GREEN (-3125 2125);
DISPLAY INVISIBLE (-3125 2125);
FORCEPROP 1 LAST HDL_TAP TRUE
J 0
(-2800 2050);
DISPLAY 1.234043 (-2800 2050);
PAINT GREEN (-2800 2050);
DISPLAY INVISIBLE (-2800 2050);
FORCEPROP 1 LAST PATH I144
J 0
(-3125 2175);
DISPLAY 0.936170 (-3125 2175);
PAINT GREEN (-3125 2175);
DISPLAY INVISIBLE (-3125 2175);
FORCEADD TAP..6
(-3125 2025);
FORCEPROP 3 LASTPIN (-3075 2025) SIG_NAME M_G_ECC<1>
J 0
(-3065 2035);
DISPLAY 0.659574 (-3065 2035);
PAINT MONO (-3065 2035);
DISPLAY INVISIBLE (-3065 2035);
FORCEPROP 1 LASTPIN (-3075 2025) BN 1
J 0
(-3125 2035);
DISPLAY 0.617021 (-3125 2035);
PAINT PINK (-3125 2035);
FORCEPROP 2 LAST CDS_LIB mstr_standard
J 0
(-3125 2025);
DISPLAY 0.787234 (-3125 2025);
PAINT MONO (-3125 2025);
DISPLAY INVISIBLE (-3125 2025);
FORCEPROP 1 LAST BODY_TYPE PLUMBING
J 0
(-3125 1975);
DISPLAY 1.234043 (-3125 1975);
PAINT GREEN (-3125 1975);
DISPLAY INVISIBLE (-3125 1975);
FORCEPROP 1 LAST HDL_TAP TRUE
J 0
(-2800 1900);
DISPLAY 1.234043 (-2800 1900);
PAINT GREEN (-2800 1900);
DISPLAY INVISIBLE (-2800 1900);
FORCEPROP 1 LAST PATH I145
J 0
(-3125 2025);
DISPLAY 0.936170 (-3125 2025);
PAINT GREEN (-3125 2025);
DISPLAY INVISIBLE (-3125 2025);
FORCEADD OFFPAGE..1
(-3925 1725);
FORCEPROP 2 LAST $XR0 57 
J 0
(-4176 1725);
DISPLAY 0.638298 (-4176 1725);
PAINT MONO (-4176 1725);
FORCEPROP 2 LAST $XR1 78 
J 0
(-4266 1725);
DISPLAY 0.638298 (-4266 1725);
PAINT MONO (-4266 1725);
FORCEPROP 2 LAST CDS_LIB mstr_standard
J 0
(-3925 1725);
DISPLAY 0.787234 (-3925 1725);
PAINT MONO (-3925 1725);
DISPLAY INVISIBLE (-3925 1725);
FORCEPROP 1 LAST OFFPAGE TRUE
J 0
(-3600 1600);
DISPLAY 0.936170 (-3600 1600);
PAINT GREEN (-3600 1600);
DISPLAY INVISIBLE (-3600 1600);
FORCEPROP 1 LAST COMMENT_BODY TRUE
J 0
(-3800 1625);
DISPLAY 0.936170 (-3800 1625);
PAINT GREEN (-3800 1625);
DISPLAY INVISIBLE (-3800 1625);
FORCEPROP 2 LAST PATH I147
J 0
(-3875 1800);
DISPLAY 0.787234 (-3875 1800);
PAINT MONO (-3875 1800);
DISPLAY INVISIBLE (-3875 1800);
FORCEADD OFFPAGE..5
(-3950 1775);
FORCEPROP 2 LAST $XR0 78 
J 0
(-4204 1775);
DISPLAY 0.638298 (-4204 1775);
PAINT MONO (-4204 1775);
FORCEPROP 2 LAST $XR1 57 
J 0
(-4294 1775);
DISPLAY 0.638298 (-4294 1775);
PAINT MONO (-4294 1775);
FORCEPROP 2 LAST CDS_LIB mstr_standard
J 0
(-3950 1775);
DISPLAY 0.787234 (-3950 1775);
PAINT MONO (-3950 1775);
DISPLAY INVISIBLE (-3950 1775);
FORCEPROP 1 LAST OFFPAGE TRUE
J 0
(-3625 1650);
DISPLAY 1.404255 (-3625 1650);
PAINT GREEN (-3625 1650);
DISPLAY INVISIBLE (-3625 1650);
FORCEPROP 1 LAST COMMENT_BODY TRUE
J 0
(-3850 1700);
DISPLAY 1.404255 (-3850 1700);
PAINT GREEN (-3850 1700);
DISPLAY INVISIBLE (-3850 1700);
FORCEPROP 2 LAST PATH I148
J 0
(-3900 1850);
DISPLAY 0.787234 (-3900 1850);
PAINT MONO (-3900 1850);
DISPLAY INVISIBLE (-3900 1850);
FORCEADD OFFPAGE..1
(-3775 2325);
FORCEPROP 2 LAST $XR0 55 
J 0
(-3996 2325);
DISPLAY 0.638298 (-3996 2325);
PAINT MONO (-3996 2325);
FORCEPROP 2 LAST $XR1 78 
J 0
(-4086 2325);
DISPLAY 0.638298 (-4086 2325);
PAINT MONO (-4086 2325);
FORCEPROP 2 LAST $XR2 79 
J 0
(-4176 2325);
DISPLAY 0.638298 (-4176 2325);
PAINT MONO (-4176 2325);
FORCEPROP 2 LAST $XR3 80 
J 0
(-4266 2325);
DISPLAY 0.638298 (-4266 2325);
PAINT MONO (-4266 2325);
FORCEPROP 2 LAST $XR4 81 
J 0
(-4356 2325);
DISPLAY 0.638298 (-4356 2325);
PAINT MONO (-4356 2325);
FORCEPROP 2 LAST $XR5 82 
J 0
(-4446 2325);
DISPLAY 0.638298 (-4446 2325);
PAINT MONO (-4446 2325);
FORCEPROP 2 LAST CDS_LIB mstr_standard
J 0
(-3775 2325);
DISPLAY 0.787234 (-3775 2325);
PAINT MONO (-3775 2325);
DISPLAY INVISIBLE (-3775 2325);
FORCEPROP 1 LAST OFFPAGE TRUE
J 0
(-3450 2200);
DISPLAY 0.936170 (-3450 2200);
PAINT GREEN (-3450 2200);
DISPLAY INVISIBLE (-3450 2200);
FORCEPROP 1 LAST COMMENT_BODY TRUE
J 0
(-3650 2225);
DISPLAY 0.936170 (-3650 2225);
PAINT GREEN (-3650 2225);
DISPLAY INVISIBLE (-3650 2225);
FORCEPROP 2 LAST PATH I149
J 0
(-3725 2400);
DISPLAY 0.787234 (-3725 2400);
PAINT MONO (-3725 2400);
DISPLAY INVISIBLE (-3725 2400);
FORCEADD TAP..6
R 2
(700 4650);
FORCEPROP 3 LASTPIN (650 4650) SIG_NAME M_G_DQS_DP<13>
J 0
(660 4660);
DISPLAY 0.659574 (660 4660);
PAINT MONO (660 4660);
DISPLAY INVISIBLE (660 4660);
FORCEPROP 1 LASTPIN (650 4650) BN 13
J 2
(700 4660);
DISPLAY 0.617021 (700 4660);
PAINT PINK (700 4660);
FORCEPROP 2 LAST CDS_LIB mstr_standard
J 0
(700 4650);
DISPLAY 0.787234 (700 4650);
PAINT MONO (700 4650);
DISPLAY INVISIBLE (700 4650);
FORCEPROP 1 LAST BODY_TYPE PLUMBING
J 2
(700 4600);
DISPLAY 1.234043 (700 4600);
PAINT GREEN (700 4600);
DISPLAY INVISIBLE (700 4600);
FORCEPROP 1 LAST HDL_TAP TRUE
J 2
(375 4525);
DISPLAY 1.234043 (375 4525);
PAINT GREEN (375 4525);
DISPLAY INVISIBLE (375 4525);
FORCEPROP 1 LAST PATH I15
J 2
(700 4650);
DISPLAY 0.936170 (700 4650);
PAINT GREEN (700 4650);
DISPLAY INVISIBLE (700 4650);
FORCEADD OFFPAGE..6
(-3775 2425);
FORCEPROP 2 LAST $XR0 57 
J 0
(-4024 2425);
DISPLAY 0.638298 (-4024 2425);
PAINT MONO (-4024 2425);
FORCEPROP 2 LAST $XR1 78 
J 0
(-4114 2425);
DISPLAY 0.638298 (-4114 2425);
PAINT MONO (-4114 2425);
FORCEPROP 2 LAST CDS_LIB mstr_standard
J 0
(-3775 2425);
DISPLAY 0.787234 (-3775 2425);
PAINT MONO (-3775 2425);
DISPLAY INVISIBLE (-3775 2425);
FORCEPROP 1 LAST OFFPAGE TRUE
J 0
(-3450 2300);
DISPLAY 0.936170 (-3450 2300);
PAINT GREEN (-3450 2300);
DISPLAY INVISIBLE (-3450 2300);
FORCEPROP 1 LAST COMMENT_BODY TRUE
J 0
(-3675 2350);
DISPLAY 0.936170 (-3675 2350);
PAINT GREEN (-3675 2350);
DISPLAY INVISIBLE (-3675 2350);
FORCEPROP 2 LAST PATH I150
J 0
(-3725 2500);
DISPLAY 0.787234 (-3725 2500);
PAINT MONO (-3725 2500);
DISPLAY INVISIBLE (-3725 2500);
FORCEADD TAP..6
(-3125 3225);
FORCEPROP 3 LASTPIN (-3075 3225) SIG_NAME M_G_CLK_DP<1>
J 0
(-3065 3235);
DISPLAY 0.659574 (-3065 3235);
PAINT MONO (-3065 3235);
DISPLAY INVISIBLE (-3065 3235);
FORCEPROP 1 LASTPIN (-3075 3225) BN 1
J 0
(-3125 3235);
DISPLAY 0.617021 (-3125 3235);
PAINT PINK (-3125 3235);
FORCEPROP 2 LAST CDS_LIB mstr_standard
J 0
(-3125 3225);
DISPLAY 0.787234 (-3125 3225);
PAINT MONO (-3125 3225);
DISPLAY INVISIBLE (-3125 3225);
FORCEPROP 1 LAST BODY_TYPE PLUMBING
J 0
(-3125 3175);
DISPLAY 1.234043 (-3125 3175);
PAINT GREEN (-3125 3175);
DISPLAY INVISIBLE (-3125 3175);
FORCEPROP 1 LAST HDL_TAP TRUE
J 0
(-2800 3100);
DISPLAY 1.234043 (-2800 3100);
PAINT GREEN (-2800 3100);
DISPLAY INVISIBLE (-2800 3100);
FORCEPROP 1 LAST PATH I152
J 0
(-3125 3225);
DISPLAY 0.936170 (-3125 3225);
PAINT GREEN (-3125 3225);
DISPLAY INVISIBLE (-3125 3225);
FORCEADD TAP..6
(-3125 3125);
FORCEPROP 3 LASTPIN (-3075 3125) SIG_NAME M_G_CLK_DP<0>
J 0
(-3065 3135);
DISPLAY 0.659574 (-3065 3135);
PAINT MONO (-3065 3135);
DISPLAY INVISIBLE (-3065 3135);
FORCEPROP 1 LASTPIN (-3075 3125) BN 0
J 0
(-3125 3135);
DISPLAY 0.617021 (-3125 3135);
PAINT PINK (-3125 3135);
FORCEPROP 2 LAST CDS_LIB mstr_standard
J 0
(-3125 3125);
DISPLAY 0.787234 (-3125 3125);
PAINT MONO (-3125 3125);
DISPLAY INVISIBLE (-3125 3125);
FORCEPROP 1 LAST BODY_TYPE PLUMBING
J 0
(-3125 3075);
DISPLAY 1.234043 (-3125 3075);
PAINT GREEN (-3125 3075);
DISPLAY INVISIBLE (-3125 3075);
FORCEPROP 1 LAST HDL_TAP TRUE
J 0
(-2800 3000);
DISPLAY 1.234043 (-2800 3000);
PAINT GREEN (-2800 3000);
DISPLAY INVISIBLE (-2800 3000);
FORCEPROP 1 LAST PATH I153
J 0
(-3125 3125);
DISPLAY 0.936170 (-3125 3125);
PAINT GREEN (-3125 3125);
DISPLAY INVISIBLE (-3125 3125);
FORCEADD OFFPAGE..1
(-3775 3300);
FORCEPROP 2 LAST $XR0 57 
J 0
(-3996 3300);
DISPLAY 0.638298 (-3996 3300);
PAINT MONO (-3996 3300);
FORCEPROP 2 LAST $XR1 78 
J 0
(-4086 3300);
DISPLAY 0.638298 (-4086 3300);
PAINT MONO (-4086 3300);
FORCEPROP 2 LAST CDS_LIB mstr_standard
J 0
(-3775 3300);
DISPLAY 0.787234 (-3775 3300);
PAINT MONO (-3775 3300);
DISPLAY INVISIBLE (-3775 3300);
FORCEPROP 1 LAST OFFPAGE TRUE
J 0
(-3450 3175);
DISPLAY 0.936170 (-3450 3175);
PAINT GREEN (-3450 3175);
DISPLAY INVISIBLE (-3450 3175);
FORCEPROP 1 LAST COMMENT_BODY TRUE
J 0
(-3650 3200);
DISPLAY 0.936170 (-3650 3200);
PAINT GREEN (-3650 3200);
DISPLAY INVISIBLE (-3650 3200);
FORCEPROP 2 LAST PATH I154
J 0
(-3725 3375);
DISPLAY 0.787234 (-3725 3375);
PAINT MONO (-3725 3375);
DISPLAY INVISIBLE (-3725 3375);
FORCEADD OFFPAGE..1
(-3775 3250);
FORCEPROP 2 LAST $XR0 57 
J 0
(-3996 3250);
DISPLAY 0.638298 (-3996 3250);
PAINT MONO (-3996 3250);
FORCEPROP 2 LAST $XR1 78 
J 0
(-4086 3250);
DISPLAY 0.638298 (-4086 3250);
PAINT MONO (-4086 3250);
FORCEPROP 2 LAST CDS_LIB mstr_standard
J 0
(-3775 3250);
DISPLAY 0.787234 (-3775 3250);
PAINT MONO (-3775 3250);
DISPLAY INVISIBLE (-3775 3250);
FORCEPROP 1 LAST OFFPAGE TRUE
J 0
(-3450 3125);
DISPLAY 0.936170 (-3450 3125);
PAINT GREEN (-3450 3125);
DISPLAY INVISIBLE (-3450 3125);
FORCEPROP 1 LAST COMMENT_BODY TRUE
J 0
(-3650 3150);
DISPLAY 0.936170 (-3650 3150);
PAINT GREEN (-3650 3150);
DISPLAY INVISIBLE (-3650 3150);
FORCEPROP 2 LAST PATH I155
J 0
(-3725 3325);
DISPLAY 0.787234 (-3725 3325);
PAINT MONO (-3725 3325);
DISPLAY INVISIBLE (-3725 3325);
FORCEADD TAP..6
(-3325 3175);
FORCEPROP 3 LASTPIN (-3275 3175) SIG_NAME M_G_CLK_DN<1>
J 0
(-3265 3185);
DISPLAY 0.659574 (-3265 3185);
PAINT MONO (-3265 3185);
DISPLAY INVISIBLE (-3265 3185);
FORCEPROP 1 LASTPIN (-3275 3175) BN 1
J 0
(-3325 3185);
DISPLAY 0.617021 (-3325 3185);
PAINT PINK (-3325 3185);
FORCEPROP 2 LAST CDS_LIB mstr_standard
J 0
(-3325 3175);
DISPLAY 0.787234 (-3325 3175);
PAINT MONO (-3325 3175);
DISPLAY INVISIBLE (-3325 3175);
FORCEPROP 1 LAST BODY_TYPE PLUMBING
J 0
(-3325 3125);
DISPLAY 1.234043 (-3325 3125);
PAINT GREEN (-3325 3125);
DISPLAY INVISIBLE (-3325 3125);
FORCEPROP 1 LAST HDL_TAP TRUE
J 0
(-3000 3050);
DISPLAY 1.234043 (-3000 3050);
PAINT GREEN (-3000 3050);
DISPLAY INVISIBLE (-3000 3050);
FORCEPROP 1 LAST PATH I156
J 0
(-3325 3175);
DISPLAY 0.936170 (-3325 3175);
PAINT GREEN (-3325 3175);
DISPLAY INVISIBLE (-3325 3175);
FORCEADD TAP..6
(-3325 3075);
FORCEPROP 3 LASTPIN (-3275 3075) SIG_NAME M_G_CLK_DN<0>
J 0
(-3265 3085);
DISPLAY 0.659574 (-3265 3085);
PAINT MONO (-3265 3085);
DISPLAY INVISIBLE (-3265 3085);
FORCEPROP 1 LASTPIN (-3275 3075) BN 0
J 0
(-3325 3085);
DISPLAY 0.617021 (-3325 3085);
PAINT PINK (-3325 3085);
FORCEPROP 2 LAST CDS_LIB mstr_standard
J 0
(-3325 3075);
DISPLAY 0.787234 (-3325 3075);
PAINT MONO (-3325 3075);
DISPLAY INVISIBLE (-3325 3075);
FORCEPROP 1 LAST BODY_TYPE PLUMBING
J 0
(-3325 3025);
DISPLAY 1.234043 (-3325 3025);
PAINT GREEN (-3325 3025);
DISPLAY INVISIBLE (-3325 3025);
FORCEPROP 1 LAST HDL_TAP TRUE
J 0
(-3000 2950);
DISPLAY 1.234043 (-3000 2950);
PAINT GREEN (-3000 2950);
DISPLAY INVISIBLE (-3000 2950);
FORCEPROP 1 LAST PATH I157
J 0
(-3325 3075);
DISPLAY 0.936170 (-3325 3075);
PAINT GREEN (-3325 3075);
DISPLAY INVISIBLE (-3325 3075);
FORCEADD TAP..6
(-3125 2925);
FORCEPROP 3 LASTPIN (-3075 2925) SIG_NAME M_G_CS_N<3>
J 0
(-3065 2935);
DISPLAY 0.659574 (-3065 2935);
PAINT MONO (-3065 2935);
DISPLAY INVISIBLE (-3065 2935);
FORCEPROP 1 LASTPIN (-3075 2925) BN 3
J 0
(-3125 2935);
DISPLAY 0.617021 (-3125 2935);
PAINT PINK (-3125 2935);
FORCEPROP 2 LAST CDS_LIB mstr_standard
J 0
(-3125 2925);
DISPLAY 0.787234 (-3125 2925);
PAINT MONO (-3125 2925);
DISPLAY INVISIBLE (-3125 2925);
FORCEPROP 1 LAST BODY_TYPE PLUMBING
J 0
(-3125 2875);
DISPLAY 1.234043 (-3125 2875);
PAINT GREEN (-3125 2875);
DISPLAY INVISIBLE (-3125 2875);
FORCEPROP 1 LAST HDL_TAP TRUE
J 0
(-2800 2800);
DISPLAY 1.234043 (-2800 2800);
PAINT GREEN (-2800 2800);
DISPLAY INVISIBLE (-2800 2800);
FORCEPROP 1 LAST PATH I158
J 0
(-3125 2925);
DISPLAY 0.936170 (-3125 2925);
PAINT GREEN (-3125 2925);
DISPLAY INVISIBLE (-3125 2925);
FORCEADD TAP..6
(-3125 2875);
FORCEPROP 3 LASTPIN (-3075 2875) SIG_NAME M_G_CS_N<2>
J 0
(-3065 2885);
DISPLAY 0.659574 (-3065 2885);
PAINT MONO (-3065 2885);
DISPLAY INVISIBLE (-3065 2885);
FORCEPROP 1 LASTPIN (-3075 2875) BN 2
J 0
(-3125 2885);
DISPLAY 0.617021 (-3125 2885);
PAINT PINK (-3125 2885);
FORCEPROP 2 LAST CDS_LIB mstr_standard
J 0
(-3125 2875);
DISPLAY 0.787234 (-3125 2875);
PAINT MONO (-3125 2875);
DISPLAY INVISIBLE (-3125 2875);
FORCEPROP 1 LAST BODY_TYPE PLUMBING
J 0
(-3125 2825);
DISPLAY 1.234043 (-3125 2825);
PAINT GREEN (-3125 2825);
DISPLAY INVISIBLE (-3125 2825);
FORCEPROP 1 LAST HDL_TAP TRUE
J 0
(-2800 2750);
DISPLAY 1.234043 (-2800 2750);
PAINT GREEN (-2800 2750);
DISPLAY INVISIBLE (-2800 2750);
FORCEPROP 1 LAST PATH I159
J 0
(-3125 2875);
DISPLAY 0.936170 (-3125 2875);
PAINT GREEN (-3125 2875);
DISPLAY INVISIBLE (-3125 2875);
FORCEADD PVDDQ_GHJ..1
(-1350 2500);
FORCEPROP 3 LASTPIN (-1350 2450) SIG_NAME PVDDQ_GHJ\g
J 0
(-1340 2460);
DISPLAY 0.659574 (-1340 2460);
PAINT MONO (-1340 2460);
DISPLAY INVISIBLE (-1340 2460);
FORCEPROP 1 LAST VOLTAGE 1.2V
J 0
(-1395 2457);
DISPLAY 0.340426 (-1395 2457);
PAINT SKYBLUE (-1395 2457);
DISPLAY INVISIBLE (-1395 2457);
FORCEPROP 2 LAST BOM_COST MEM
J 0
(-1350 2505);
PAINT ORANGE (-1350 2505);
DISPLAY INVISIBLE (-1350 2505);
FORCEPROP 2 LAST CDS_LIB mstr_symbols
J 0
(-1350 2500);
PAINT ORANGE (-1350 2500);
DISPLAY INVISIBLE (-1350 2500);
FORCEPROP 1 LAST BODY_TYPE PLUMBING
J 0
(-1395 2457);
DISPLAY 0.340426 (-1395 2457);
PAINT GREEN (-1395 2457);
DISPLAY INVISIBLE (-1395 2457);
FORCEPROP 1 LAST PATH I16
J 0
(-1300 2525);
DISPLAY 0.872340 (-1300 2525);
PAINT AQUA (-1300 2525);
DISPLAY INVISIBLE (-1300 2525);
FORCEPROP 2 LAST ROOM DDR4_CH_G
J 0
(-1350 2600);
DISPLAY 0.787234 (-1350 2600);
PAINT ORANGE (-1350 2600);
DISPLAY INVISIBLE (-1350 2600);
FORCEPROP 1 LAST HDL_POWER PVDDQ_GHJ
J 1
(-1350 2550);
DISPLAY 0.872340 (-1350 2550);
PAINT GREEN (-1350 2550);
DISPLAY INVISIBLE (-1350 2550);
FORCEADD TAP..6
(-3125 2825);
FORCEPROP 3 LASTPIN (-3075 2825) SIG_NAME M_G_CS_N<1>
J 0
(-3065 2835);
DISPLAY 0.659574 (-3065 2835);
PAINT MONO (-3065 2835);
DISPLAY INVISIBLE (-3065 2835);
FORCEPROP 1 LASTPIN (-3075 2825) BN 1
J 0
(-3125 2835);
DISPLAY 0.617021 (-3125 2835);
PAINT PINK (-3125 2835);
FORCEPROP 2 LAST CDS_LIB mstr_standard
J 0
(-3125 2825);
DISPLAY 0.787234 (-3125 2825);
PAINT MONO (-3125 2825);
DISPLAY INVISIBLE (-3125 2825);
FORCEPROP 1 LAST BODY_TYPE PLUMBING
J 0
(-3125 2775);
DISPLAY 1.234043 (-3125 2775);
PAINT GREEN (-3125 2775);
DISPLAY INVISIBLE (-3125 2775);
FORCEPROP 1 LAST HDL_TAP TRUE
J 0
(-2800 2700);
DISPLAY 1.234043 (-2800 2700);
PAINT GREEN (-2800 2700);
DISPLAY INVISIBLE (-2800 2700);
FORCEPROP 1 LAST PATH I160
J 0
(-3125 2825);
DISPLAY 0.936170 (-3125 2825);
PAINT GREEN (-3125 2825);
DISPLAY INVISIBLE (-3125 2825);
FORCEADD TAP..6
(-3125 2775);
FORCEPROP 3 LASTPIN (-3075 2775) SIG_NAME M_G_CS_N<0>
J 0
(-3065 2785);
DISPLAY 0.659574 (-3065 2785);
PAINT MONO (-3065 2785);
DISPLAY INVISIBLE (-3065 2785);
FORCEPROP 1 LASTPIN (-3075 2775) BN 0
J 0
(-3125 2785);
DISPLAY 0.617021 (-3125 2785);
PAINT PINK (-3125 2785);
FORCEPROP 2 LAST CDS_LIB mstr_standard
J 0
(-3125 2775);
DISPLAY 0.787234 (-3125 2775);
PAINT MONO (-3125 2775);
DISPLAY INVISIBLE (-3125 2775);
FORCEPROP 1 LAST BODY_TYPE PLUMBING
J 0
(-3125 2725);
DISPLAY 1.234043 (-3125 2725);
PAINT GREEN (-3125 2725);
DISPLAY INVISIBLE (-3125 2725);
FORCEPROP 1 LAST HDL_TAP TRUE
J 0
(-2800 2650);
DISPLAY 1.234043 (-2800 2650);
PAINT GREEN (-2800 2650);
DISPLAY INVISIBLE (-2800 2650);
FORCEPROP 1 LAST PATH I161
J 0
(-3125 2775);
DISPLAY 0.936170 (-3125 2775);
PAINT GREEN (-3125 2775);
DISPLAY INVISIBLE (-3125 2775);
FORCEADD TAP..6
(-3125 2675);
FORCEPROP 3 LASTPIN (-3075 2675) SIG_NAME M_G_CKE<1>
J 0
(-3065 2685);
DISPLAY 0.659574 (-3065 2685);
PAINT MONO (-3065 2685);
DISPLAY INVISIBLE (-3065 2685);
FORCEPROP 1 LASTPIN (-3075 2675) BN 1
J 0
(-3125 2685);
DISPLAY 0.617021 (-3125 2685);
PAINT PINK (-3125 2685);
FORCEPROP 2 LAST CDS_LIB mstr_standard
J 0
(-3125 2675);
DISPLAY 0.787234 (-3125 2675);
PAINT MONO (-3125 2675);
DISPLAY INVISIBLE (-3125 2675);
FORCEPROP 1 LAST BODY_TYPE PLUMBING
J 0
(-3125 2625);
DISPLAY 1.234043 (-3125 2625);
PAINT GREEN (-3125 2625);
DISPLAY INVISIBLE (-3125 2625);
FORCEPROP 1 LAST HDL_TAP TRUE
J 0
(-2800 2550);
DISPLAY 1.234043 (-2800 2550);
PAINT GREEN (-2800 2550);
DISPLAY INVISIBLE (-2800 2550);
FORCEPROP 1 LAST PATH I162
J 0
(-3125 2675);
DISPLAY 0.936170 (-3125 2675);
PAINT GREEN (-3125 2675);
DISPLAY INVISIBLE (-3125 2675);
FORCEADD OFFPAGE..1
(-3775 2975);
FORCEPROP 2 LAST $XR0 57 
J 0
(-3996 2975);
DISPLAY 0.638298 (-3996 2975);
PAINT MONO (-3996 2975);
FORCEPROP 2 LAST $XR1 78 
J 0
(-4086 2975);
DISPLAY 0.638298 (-4086 2975);
PAINT MONO (-4086 2975);
FORCEPROP 2 LAST CDS_LIB mstr_standard
J 0
(-3775 2975);
DISPLAY 0.787234 (-3775 2975);
PAINT MONO (-3775 2975);
DISPLAY INVISIBLE (-3775 2975);
FORCEPROP 1 LAST OFFPAGE TRUE
J 0
(-3450 2850);
DISPLAY 0.936170 (-3450 2850);
PAINT GREEN (-3450 2850);
DISPLAY INVISIBLE (-3450 2850);
FORCEPROP 1 LAST COMMENT_BODY TRUE
J 0
(-3650 2875);
DISPLAY 0.936170 (-3650 2875);
PAINT GREEN (-3650 2875);
DISPLAY INVISIBLE (-3650 2875);
FORCEPROP 2 LAST PATH I163
J 0
(-3725 3050);
DISPLAY 0.787234 (-3725 3050);
PAINT MONO (-3725 3050);
DISPLAY INVISIBLE (-3725 3050);
FORCEADD OFFPAGE..1
(-3775 2725);
FORCEPROP 2 LAST $XR0 57 
J 0
(-3996 2725);
DISPLAY 0.638298 (-3996 2725);
PAINT MONO (-3996 2725);
FORCEPROP 2 LAST $XR1 78 
J 0
(-4086 2725);
DISPLAY 0.638298 (-4086 2725);
PAINT MONO (-4086 2725);
FORCEPROP 2 LAST CDS_LIB mstr_standard
J 0
(-3775 2725);
DISPLAY 0.787234 (-3775 2725);
PAINT MONO (-3775 2725);
DISPLAY INVISIBLE (-3775 2725);
FORCEPROP 1 LAST OFFPAGE TRUE
J 0
(-3450 2600);
DISPLAY 0.936170 (-3450 2600);
PAINT GREEN (-3450 2600);
DISPLAY INVISIBLE (-3450 2600);
FORCEPROP 1 LAST COMMENT_BODY TRUE
J 0
(-3650 2625);
DISPLAY 0.936170 (-3650 2625);
PAINT GREEN (-3650 2625);
DISPLAY INVISIBLE (-3650 2625);
FORCEPROP 2 LAST PATH I164
J 0
(-3725 2800);
DISPLAY 0.787234 (-3725 2800);
PAINT MONO (-3725 2800);
DISPLAY INVISIBLE (-3725 2800);
FORCEADD TAP..6
(-3125 2625);
FORCEPROP 3 LASTPIN (-3075 2625) SIG_NAME M_G_CKE<0>
J 0
(-3065 2635);
DISPLAY 0.659574 (-3065 2635);
PAINT MONO (-3065 2635);
DISPLAY INVISIBLE (-3065 2635);
FORCEPROP 1 LASTPIN (-3075 2625) BN 0
J 0
(-3125 2635);
DISPLAY 0.617021 (-3125 2635);
PAINT PINK (-3125 2635);
FORCEPROP 2 LAST CDS_LIB mstr_standard
J 0
(-3125 2625);
DISPLAY 0.787234 (-3125 2625);
PAINT MONO (-3125 2625);
DISPLAY INVISIBLE (-3125 2625);
FORCEPROP 1 LAST BODY_TYPE PLUMBING
J 0
(-3125 2575);
DISPLAY 1.234043 (-3125 2575);
PAINT GREEN (-3125 2575);
DISPLAY INVISIBLE (-3125 2575);
FORCEPROP 1 LAST HDL_TAP TRUE
J 0
(-2800 2500);
DISPLAY 1.234043 (-2800 2500);
PAINT GREEN (-2800 2500);
DISPLAY INVISIBLE (-2800 2500);
FORCEPROP 1 LAST PATH I165
J 0
(-3125 2625);
DISPLAY 0.936170 (-3125 2625);
PAINT GREEN (-3125 2625);
DISPLAY INVISIBLE (-3125 2625);
FORCEADD TAP..6
(-3125 2525);
FORCEPROP 3 LASTPIN (-3075 2525) SIG_NAME M_G_ODT<1>
J 0
(-3065 2535);
DISPLAY 0.659574 (-3065 2535);
PAINT MONO (-3065 2535);
DISPLAY INVISIBLE (-3065 2535);
FORCEPROP 1 LASTPIN (-3075 2525) BN 1
J 0
(-3125 2535);
DISPLAY 0.617021 (-3125 2535);
PAINT PINK (-3125 2535);
FORCEPROP 2 LAST CDS_LIB mstr_standard
J 0
(-3125 2525);
DISPLAY 0.787234 (-3125 2525);
PAINT MONO (-3125 2525);
DISPLAY INVISIBLE (-3125 2525);
FORCEPROP 1 LAST BODY_TYPE PLUMBING
J 0
(-3125 2475);
DISPLAY 1.234043 (-3125 2475);
PAINT GREEN (-3125 2475);
DISPLAY INVISIBLE (-3125 2475);
FORCEPROP 1 LAST HDL_TAP TRUE
J 0
(-2800 2400);
DISPLAY 1.234043 (-2800 2400);
PAINT GREEN (-2800 2400);
DISPLAY INVISIBLE (-2800 2400);
FORCEPROP 1 LAST PATH I166
J 0
(-3125 2525);
DISPLAY 0.936170 (-3125 2525);
PAINT GREEN (-3125 2525);
DISPLAY INVISIBLE (-3125 2525);
FORCEADD OFFPAGE..1
(-3775 2575);
FORCEPROP 2 LAST $XR0 57 
J 0
(-3996 2575);
DISPLAY 0.638298 (-3996 2575);
PAINT MONO (-3996 2575);
FORCEPROP 2 LAST $XR1 78 
J 0
(-4086 2575);
DISPLAY 0.638298 (-4086 2575);
PAINT MONO (-4086 2575);
FORCEPROP 2 LAST CDS_LIB mstr_standard
J 0
(-3775 2575);
DISPLAY 0.787234 (-3775 2575);
PAINT MONO (-3775 2575);
DISPLAY INVISIBLE (-3775 2575);
FORCEPROP 1 LAST OFFPAGE TRUE
J 0
(-3450 2450);
DISPLAY 0.936170 (-3450 2450);
PAINT GREEN (-3450 2450);
DISPLAY INVISIBLE (-3450 2450);
FORCEPROP 1 LAST COMMENT_BODY TRUE
J 0
(-3650 2475);
DISPLAY 0.936170 (-3650 2475);
PAINT GREEN (-3650 2475);
DISPLAY INVISIBLE (-3650 2475);
FORCEPROP 2 LAST PATH I167
J 0
(-3725 2650);
DISPLAY 0.787234 (-3725 2650);
PAINT MONO (-3725 2650);
DISPLAY INVISIBLE (-3725 2650);
FORCEADD TAP..6
(-3125 2475);
FORCEPROP 3 LASTPIN (-3075 2475) SIG_NAME M_G_ODT<0>
J 0
(-3065 2485);
DISPLAY 0.659574 (-3065 2485);
PAINT MONO (-3065 2485);
DISPLAY INVISIBLE (-3065 2485);
FORCEPROP 1 LASTPIN (-3075 2475) BN 0
J 0
(-3125 2485);
DISPLAY 0.617021 (-3125 2485);
PAINT PINK (-3125 2485);
FORCEPROP 2 LAST CDS_LIB mstr_standard
J 0
(-3125 2475);
DISPLAY 0.787234 (-3125 2475);
PAINT MONO (-3125 2475);
DISPLAY INVISIBLE (-3125 2475);
FORCEPROP 1 LAST BODY_TYPE PLUMBING
J 0
(-3125 2425);
DISPLAY 1.234043 (-3125 2425);
PAINT GREEN (-3125 2425);
DISPLAY INVISIBLE (-3125 2425);
FORCEPROP 1 LAST HDL_TAP TRUE
J 0
(-2800 2350);
DISPLAY 1.234043 (-2800 2350);
PAINT GREEN (-2800 2350);
DISPLAY INVISIBLE (-2800 2350);
FORCEPROP 1 LAST PATH I168
J 0
(-3125 2475);
DISPLAY 0.936170 (-3125 2475);
PAINT GREEN (-3125 2475);
DISPLAY INVISIBLE (-3125 2475);
FORCEADD PVTT_GHJ..1
(-1150 2650);
FORCEPROP 3 LASTPIN (-1150 2600) SIG_NAME PVTT_GHJ\g
J 0
(-1140 2610);
DISPLAY 0.659574 (-1140 2610);
PAINT MONO (-1140 2610);
DISPLAY INVISIBLE (-1140 2610);
FORCEPROP 1 LAST VOLTAGE 0.6V
J 0
(-1195 2607);
DISPLAY 0.340426 (-1195 2607);
PAINT SKYBLUE (-1195 2607);
DISPLAY INVISIBLE (-1195 2607);
FORCEPROP 2 LAST BOM_COST MEM
J 0
(-1150 2655);
PAINT ORANGE (-1150 2655);
DISPLAY INVISIBLE (-1150 2655);
FORCEPROP 2 LAST CDS_LIB mstr_symbols
J 0
(-1150 2650);
PAINT ORANGE (-1150 2650);
DISPLAY INVISIBLE (-1150 2650);
FORCEPROP 1 LAST BODY_TYPE PLUMBING
J 0
(-1195 2607);
DISPLAY 0.340426 (-1195 2607);
PAINT GREEN (-1195 2607);
DISPLAY INVISIBLE (-1195 2607);
FORCEPROP 1 LAST PATH I17
J 0
(-1100 2675);
DISPLAY 0.872340 (-1100 2675);
PAINT AQUA (-1100 2675);
DISPLAY INVISIBLE (-1100 2675);
FORCEPROP 2 LAST ROOM DDR4_CH_G
J 0
(-1150 2750);
DISPLAY 0.787234 (-1150 2750);
PAINT ORANGE (-1150 2750);
DISPLAY INVISIBLE (-1150 2750);
FORCEPROP 1 LAST HDL_POWER PVTT_GHJ
J 1
(-1150 2700);
DISPLAY 0.872340 (-1150 2700);
PAINT GREEN (-1150 2700);
DISPLAY INVISIBLE (-1150 2700);
FORCEADD SCONN288_H44441004..4
(-300 1950);
FORCEPROP 1 LAST LOCATION J1G1
J 0
(-750 3050);
DISPLAY 0.617021 (-750 3050);
PAINT AQUA (-750 3050);
FORCEPROP 1 LAST PART_NUMBER H44441-004
J 0
(-750 900);
DISPLAY 0.617021 (-750 900);
PAINT BLUE (-750 900);
FORCEPROP 1 LAST MATERIAL SCONN
J 0
(-750 3000);
DISPLAY 0.617021 (-750 3000);
PAINT SKYBLUE (-750 3000);
FORCEPROP 2 LASTPIN (-800 2500) $PN 77
J 2
(-810 2510);
DISPLAY 0.617021 (-810 2510);
PAINT ORANGE (-810 2510);
FORCEPROP 2 LASTPIN (-800 2450) $PN 221
J 2
(-810 2460);
DISPLAY 0.617021 (-810 2460);
PAINT ORANGE (-810 2460);
FORCEPROP 2 LASTPIN (-800 2800) $PN 142
J 2
(-810 2810);
DISPLAY 0.617021 (-810 2810);
PAINT ORANGE (-810 2810);
FORCEPROP 2 LASTPIN (-800 2750) $PN 143
J 2
(-810 2760);
DISPLAY 0.617021 (-810 2760);
PAINT ORANGE (-810 2760);
FORCEPROP 2 LASTPIN (-800 2700) $PN 288
J 2
(-810 2710);
DISPLAY 0.617021 (-810 2710);
PAINT ORANGE (-810 2710);
FORCEPROP 2 LASTPIN (-800 2650) $PN 286
J 2
(-810 2660);
DISPLAY 0.617021 (-810 2660);
PAINT ORANGE (-810 2660);
FORCEPROP 2 LASTPIN (-800 2600) $PN 287
J 2
(-810 2610);
DISPLAY 0.617021 (-810 2610);
PAINT ORANGE (-810 2610);
FORCEPROP 2 LASTPIN (-800 2350) $PN 59
J 2
(-810 2360);
DISPLAY 0.617021 (-810 2360);
PAINT ORANGE (-810 2360);
FORCEPROP 2 LASTPIN (-800 2300) $PN 61
J 2
(-810 2310);
DISPLAY 0.617021 (-810 2310);
PAINT ORANGE (-810 2310);
FORCEPROP 2 LASTPIN (-800 2250) $PN 64
J 2
(-810 2260);
DISPLAY 0.617021 (-810 2260);
PAINT ORANGE (-810 2260);
FORCEPROP 2 LASTPIN (-800 2200) $PN 67
J 2
(-810 2210);
DISPLAY 0.617021 (-810 2210);
PAINT ORANGE (-810 2210);
FORCEPROP 2 LASTPIN (-800 2150) $PN 70
J 2
(-810 2160);
DISPLAY 0.617021 (-810 2160);
PAINT ORANGE (-810 2160);
FORCEPROP 2 LASTPIN (-800 2100) $PN 73
J 2
(-810 2110);
DISPLAY 0.617021 (-810 2110);
PAINT ORANGE (-810 2110);
FORCEPROP 2 LASTPIN (-800 2050) $PN 76
J 2
(-810 2060);
DISPLAY 0.617021 (-810 2060);
PAINT ORANGE (-810 2060);
FORCEPROP 2 LASTPIN (-800 2000) $PN 80
J 2
(-810 2010);
DISPLAY 0.617021 (-810 2010);
PAINT ORANGE (-810 2010);
FORCEPROP 2 LASTPIN (-800 1950) $PN 83
J 2
(-810 1960);
DISPLAY 0.617021 (-810 1960);
PAINT ORANGE (-810 1960);
FORCEPROP 2 LASTPIN (-800 1900) $PN 85
J 2
(-810 1910);
DISPLAY 0.617021 (-810 1910);
PAINT ORANGE (-810 1910);
FORCEPROP 2 LASTPIN (-800 1850) $PN 88
J 2
(-810 1860);
DISPLAY 0.617021 (-810 1860);
PAINT ORANGE (-810 1860);
FORCEPROP 2 LASTPIN (-800 1800) $PN 90
J 2
(-810 1810);
DISPLAY 0.617021 (-810 1810);
PAINT ORANGE (-810 1810);
FORCEPROP 2 LASTPIN (-800 1750) $PN 92
J 2
(-810 1760);
DISPLAY 0.617021 (-810 1760);
PAINT ORANGE (-810 1760);
FORCEPROP 2 LASTPIN (-800 1700) $PN 204
J 2
(-810 1710);
DISPLAY 0.617021 (-810 1710);
PAINT ORANGE (-810 1710);
FORCEPROP 2 LASTPIN (-800 1650) $PN 206
J 2
(-810 1660);
DISPLAY 0.617021 (-810 1660);
PAINT ORANGE (-810 1660);
FORCEPROP 2 LASTPIN (-800 1600) $PN 209
J 2
(-810 1610);
DISPLAY 0.617021 (-810 1610);
PAINT ORANGE (-810 1610);
FORCEPROP 2 LASTPIN (-800 1550) $PN 212
J 2
(-810 1560);
DISPLAY 0.617021 (-810 1560);
PAINT ORANGE (-810 1560);
FORCEPROP 2 LASTPIN (-800 1500) $PN 215
J 2
(-810 1510);
DISPLAY 0.617021 (-810 1510);
PAINT ORANGE (-810 1510);
FORCEPROP 2 LASTPIN (-800 1450) $PN 217
J 2
(-810 1460);
DISPLAY 0.617021 (-810 1460);
PAINT ORANGE (-810 1460);
FORCEPROP 2 LASTPIN (-800 1400) $PN 220
J 2
(-810 1410);
DISPLAY 0.617021 (-810 1410);
PAINT ORANGE (-810 1410);
FORCEPROP 2 LASTPIN (-800 1350) $PN 223
J 2
(-810 1360);
DISPLAY 0.617021 (-810 1360);
PAINT ORANGE (-810 1360);
FORCEPROP 2 LASTPIN (-800 1300) $PN 226
J 2
(-810 1310);
DISPLAY 0.617021 (-810 1310);
PAINT ORANGE (-810 1310);
FORCEPROP 2 LASTPIN (-800 1250) $PN 229
J 2
(-810 1260);
DISPLAY 0.617021 (-810 1260);
PAINT ORANGE (-810 1260);
FORCEPROP 2 LASTPIN (-800 1200) $PN 231
J 2
(-810 1210);
DISPLAY 0.617021 (-810 1210);
PAINT ORANGE (-810 1210);
FORCEPROP 2 LASTPIN (-800 1150) $PN 233
J 2
(-810 1160);
DISPLAY 0.617021 (-810 1160);
PAINT ORANGE (-810 1160);
FORCEPROP 2 LASTPIN (-800 1100) $PN 236
J 2
(-810 1110);
DISPLAY 0.617021 (-810 1110);
PAINT ORANGE (-810 1110);
FORCEPROP 2 LASTPIN (200 2800) $PN 1
J 0
(210 2810);
DISPLAY 0.617021 (210 2810);
PAINT ORANGE (210 2810);
FORCEPROP 2 LASTPIN (200 2750) $PN 145
J 0
(210 2760);
DISPLAY 0.617021 (210 2760);
PAINT ORANGE (210 2760);
FORCEPROP 1 LAST PACK_TYPE PIP
J 0
(-750 3100);
PAINT SKYBLUE (-750 3100);
DISPLAY INVISIBLE (-750 3100);
FORCEPROP 2 LAST BOM_COST MEM
J 0
(-300 1950);
PAINT ORANGE (-300 1950);
DISPLAY INVISIBLE (-300 1950);
FORCEPROP 2 LAST CDS_LIB mstr_sconn
J 0
(-300 1950);
PAINT ORANGE (-300 1950);
DISPLAY INVISIBLE (-300 1950);
FORCEPROP 2 LAST SEC_TYPE PIP
J 0
(-750 3100);
DISPLAY 1.021277 (-750 3100);
PAINT ORANGE (-750 3100);
DISPLAY INVISIBLE (-750 3100);
FORCEPROP 2 LAST SEC 4
J 0
(-750 3100);
DISPLAY 0.680851 (-750 3100);
PAINT MONO (-750 3100);
DISPLAY INVISIBLE (-750 3100);
FORCEPROP 2 LAST CDS_LOCATION J1G1
J 0
(-750 3050);
DISPLAY 0.617021 (-750 3050);
PAINT AQUA (-750 3050);
DISPLAY INVISIBLE (-750 3050);
FORCEPROP 1 LAST PATH I171
J 0
(-300 3000);
PAINT GREEN (-300 3000);
DISPLAY INVISIBLE (-300 3000);
FORCEPROP 2 LAST ROOM DDR4_CH_G
J 0
(-300 1950);
PAINT ORANGE (-300 1950);
DISPLAY INVISIBLE (-300 1950);
FORCEADD GND..1
R 2
(2500 900);
FORCEPROP 3 LASTPIN (2500 950) SIG_NAME GND\g
J 0
(2510 960);
DISPLAY 0.659574 (2510 960);
PAINT MONO (2510 960);
DISPLAY INVISIBLE (2510 960);
FORCEPROP 1 LAST VOLTAGE 0
J 0
(2500 900);
PAINT SKYBLUE (2500 900);
DISPLAY INVISIBLE (2500 900);
FORCEPROP 1 LAST SIZE 1B
J 2
(2425 850);
DISPLAY 1.170213 (2425 850);
PAINT GREEN (2425 850);
DISPLAY INVISIBLE (2425 850);
FORCEPROP 2 LAST CDS_LIB mstr_symbols
J 0
(2500 900);
DISPLAY 0.787234 (2500 900);
PAINT MONO (2500 900);
DISPLAY INVISIBLE (2500 900);
FORCEPROP 2 LAST BOM_COST MEM
J 0
(2500 905);
PAINT ORANGE (2500 905);
DISPLAY INVISIBLE (2500 905);
FORCEPROP 1 LAST BODY_TYPE PLUMBING
J 2
(2545 857);
DISPLAY 0.340426 (2545 857);
PAINT GREEN (2545 857);
DISPLAY INVISIBLE (2545 857);
FORCEPROP 1 LAST PATH I172
J 2
(2425 900);
DISPLAY 1.404255 (2425 900);
PAINT GREEN (2425 900);
DISPLAY INVISIBLE (2425 900);
FORCEPROP 2 LAST ROOM DDR4_CH_G
J 0
(2500 905);
PAINT ORANGE (2500 905);
DISPLAY INVISIBLE (2500 905);
FORCEPROP 1 LAST HDL_POWER GND
J 2
(2500 1050);
DISPLAY 0.553191 (2500 1050);
PAINT GREEN (2500 1050);
DISPLAY INVISIBLE (2500 1050);
FORCEADD OFFPAGE..6
(-3775 1425);
FORCEPROP 2 LAST $XR0 78 
J 0
(-4024 1425);
DISPLAY 0.638298 (-4024 1425);
PAINT MONO (-4024 1425);
FORCEPROP 2 LAST $XR1 79 
J 0
(-4114 1425);
DISPLAY 0.638298 (-4114 1425);
PAINT MONO (-4114 1425);
FORCEPROP 2 LAST $XR2 80 
J 0
(-4204 1425);
DISPLAY 0.638298 (-4204 1425);
PAINT MONO (-4204 1425);
FORCEPROP 2 LAST $XR3 81 
J 0
(-4294 1425);
DISPLAY 0.638298 (-4294 1425);
PAINT MONO (-4294 1425);
FORCEPROP 2 LAST $XR4 82 
J 0
(-4384 1425);
DISPLAY 0.638298 (-4384 1425);
PAINT MONO (-4384 1425);
FORCEPROP 2 LAST $XR5 99 
J 0
(-4474 1425);
DISPLAY 0.638298 (-4474 1425);
PAINT MONO (-4474 1425);
FORCEPROP 2 LASTPIN (-3725 1425) SIG_NAME SMB_DDR_GHJ_VPP_SDA
J 0
(-3685 1435);
DISPLAY 0.617021 (-3685 1435);
PAINT ORANGE (-3685 1435);
FORCEPROP 2 LAST CDS_LIB mstr_standard
J 0
(-3775 1425);
DISPLAY 0.787234 (-3775 1425);
PAINT MONO (-3775 1425);
DISPLAY INVISIBLE (-3775 1425);
FORCEPROP 1 LAST OFFPAGE TRUE
J 0
(-3450 1300);
DISPLAY 0.936170 (-3450 1300);
PAINT GREEN (-3450 1300);
DISPLAY INVISIBLE (-3450 1300);
FORCEPROP 1 LAST COMMENT_BODY TRUE
J 0
(-3675 1350);
DISPLAY 0.936170 (-3675 1350);
PAINT GREEN (-3675 1350);
DISPLAY INVISIBLE (-3675 1350);
FORCEPROP 2 LAST PATH I173
J 0
(-4100 1475);
DISPLAY 0.787234 (-4100 1475);
PAINT ORANGE (-4100 1475);
DISPLAY INVISIBLE (-4100 1475);
FORCEADD OFFPAGE..1
(-3775 1375);
FORCEPROP 2 LAST $XR0 99 
J 0
(-4026 1375);
DISPLAY 0.638298 (-4026 1375);
PAINT MONO (-4026 1375);
FORCEPROP 2 LAST $XR1 78 
J 0
(-4116 1375);
DISPLAY 0.638298 (-4116 1375);
PAINT MONO (-4116 1375);
FORCEPROP 2 LAST $XR2 79 
J 0
(-4206 1375);
DISPLAY 0.638298 (-4206 1375);
PAINT MONO (-4206 1375);
FORCEPROP 2 LAST $XR3 80 
J 0
(-4296 1375);
DISPLAY 0.638298 (-4296 1375);
PAINT MONO (-4296 1375);
FORCEPROP 2 LAST $XR4 81 
J 0
(-4386 1375);
DISPLAY 0.638298 (-4386 1375);
PAINT MONO (-4386 1375);
FORCEPROP 2 LAST $XR5 82 
J 0
(-4476 1375);
DISPLAY 0.638298 (-4476 1375);
PAINT MONO (-4476 1375);
FORCEPROP 2 LAST CDS_LIB mstr_standard
J 0
(-3775 1375);
DISPLAY 0.787234 (-3775 1375);
PAINT MONO (-3775 1375);
DISPLAY INVISIBLE (-3775 1375);
FORCEPROP 1 LAST OFFPAGE TRUE
J 0
(-3450 1250);
DISPLAY 0.936170 (-3450 1250);
PAINT GREEN (-3450 1250);
DISPLAY INVISIBLE (-3450 1250);
FORCEPROP 1 LAST COMMENT_BODY TRUE
J 0
(-3650 1275);
DISPLAY 0.936170 (-3650 1275);
PAINT GREEN (-3650 1275);
DISPLAY INVISIBLE (-3650 1275);
FORCEPROP 2 LAST PATH I174
J 0
(-4050 1425);
DISPLAY 0.787234 (-4050 1425);
PAINT ORANGE (-4050 1425);
DISPLAY INVISIBLE (-4050 1425);
FORCEADD OFFPAGE..1
(-4575 1275);
FORCEPROP 2 LAST $XR0 100 
J 0
(-4827 1275);
DISPLAY 0.638298 (-4827 1275);
PAINT MONO (-4827 1275);
FORCEPROP 2 LAST $XR1 78 
J 0
(-4917 1275);
DISPLAY 0.638298 (-4917 1275);
PAINT MONO (-4917 1275);
FORCEPROP 2 LAST CDS_LIB mstr_standard
J 0
(-4575 1275);
DISPLAY 0.787234 (-4575 1275);
PAINT MONO (-4575 1275);
DISPLAY INVISIBLE (-4575 1275);
FORCEPROP 1 LAST OFFPAGE TRUE
J 0
(-4250 1150);
DISPLAY 0.936170 (-4250 1150);
PAINT GREEN (-4250 1150);
DISPLAY INVISIBLE (-4250 1150);
FORCEPROP 1 LAST COMMENT_BODY TRUE
J 0
(-4450 1175);
DISPLAY 0.936170 (-4450 1175);
PAINT GREEN (-4450 1175);
DISPLAY INVISIBLE (-4450 1175);
FORCEPROP 2 LAST PATH I175
J 0
(-4825 1325);
DISPLAY 0.787234 (-4825 1325);
PAINT ORANGE (-4825 1325);
DISPLAY INVISIBLE (-4825 1325);
FORCEADD GND..1
R 2
(-5075 1425);
FORCEPROP 3 LASTPIN (-5075 1475) SIG_NAME GND\g
J 0
(-5065 1485);
DISPLAY 0.659574 (-5065 1485);
PAINT MONO (-5065 1485);
DISPLAY INVISIBLE (-5065 1485);
FORCEPROP 1 LAST VOLTAGE 0
J 0
(-5075 1425);
PAINT SKYBLUE (-5075 1425);
DISPLAY INVISIBLE (-5075 1425);
FORCEPROP 1 LAST SIZE 1B
J 2
(-5150 1375);
DISPLAY 1.170213 (-5150 1375);
PAINT GREEN (-5150 1375);
DISPLAY INVISIBLE (-5150 1375);
FORCEPROP 2 LAST CDS_LIB mstr_symbols
J 0
(-5075 1425);
DISPLAY 0.787234 (-5075 1425);
PAINT MONO (-5075 1425);
DISPLAY INVISIBLE (-5075 1425);
FORCEPROP 2 LAST BOM_COST MEM
J 0
(-5075 1430);
PAINT ORANGE (-5075 1430);
DISPLAY INVISIBLE (-5075 1430);
FORCEPROP 1 LAST BODY_TYPE PLUMBING
J 2
(-5030 1382);
DISPLAY 0.340426 (-5030 1382);
PAINT GREEN (-5030 1382);
DISPLAY INVISIBLE (-5030 1382);
FORCEPROP 1 LAST PATH I177
J 2
(-5150 1425);
DISPLAY 1.404255 (-5150 1425);
PAINT GREEN (-5150 1425);
DISPLAY INVISIBLE (-5150 1425);
FORCEPROP 2 LAST ROOM DDR4_CH_G
J 0
(-5075 1430);
PAINT ORANGE (-5075 1430);
DISPLAY INVISIBLE (-5075 1430);
FORCEPROP 1 LAST HDL_POWER GND
J 2
(-5075 1575);
DISPLAY 0.553191 (-5075 1575);
PAINT GREEN (-5075 1575);
DISPLAY INVISIBLE (-5075 1575);
FORCEADD OFFPAGE..5
(-4100 2075);
FORCEPROP 2 LAST $XR0 43 
J 0
(-4324 2075);
DISPLAY 0.638298 (-4324 2075);
PAINT MONO (-4324 2075);
FORCEPROP 2 LAST $XR1 44 
J 0
(-4414 2075);
DISPLAY 0.638298 (-4414 2075);
PAINT MONO (-4414 2075);
FORCEPROP 2 LAST $XR2 45 
J 0
(-4504 2075);
DISPLAY 0.638298 (-4504 2075);
PAINT MONO (-4504 2075);
FORCEPROP 2 LAST $XR3 46 
J 0
(-4594 2075);
DISPLAY 0.638298 (-4594 2075);
PAINT MONO (-4594 2075);
FORCEPROP 2 LAST $XR4 47 
J 0
(-4684 2075);
DISPLAY 0.638298 (-4684 2075);
PAINT MONO (-4684 2075);
FORCEPROP 2 LAST $XR5 48 
J 0
(-4774 2075);
DISPLAY 0.638298 (-4774 2075);
PAINT MONO (-4774 2075);
FORCEPROP 2 LAST $XR6 49 
J 0
(-4864 2075);
DISPLAY 0.638298 (-4864 2075);
PAINT MONO (-4864 2075);
FORCEPROP 2 LAST $XR7 50 
J 0
(-4954 2075);
DISPLAY 0.638298 (-4954 2075);
PAINT MONO (-4954 2075);
FORCEPROP 2 LAST $XR8 51 
J 0
(-5044 2075);
DISPLAY 0.638298 (-5044 2075);
PAINT MONO (-5044 2075);
FORCEPROP 2 LAST $XR9 52 
J 0
(-5134 2075);
DISPLAY 0.638298 (-5134 2075);
PAINT MONO (-5134 2075);
FORCEPROP 2 LAST $XR10 53 
J 0
(-4324 2039);
DISPLAY 0.638298 (-4324 2039);
PAINT MONO (-4324 2039);
FORCEPROP 2 LAST $XR11 54 
J 0
(-4414 2039);
DISPLAY 0.638298 (-4414 2039);
PAINT MONO (-4414 2039);
FORCEPROP 2 LAST $XR12 78 
J 0
(-4504 2039);
DISPLAY 0.638298 (-4504 2039);
PAINT MONO (-4504 2039);
FORCEPROP 2 LAST $XR13 79 
J 0
(-4594 2039);
DISPLAY 0.638298 (-4594 2039);
PAINT MONO (-4594 2039);
FORCEPROP 2 LAST $XR14 80 
J 0
(-4684 2039);
DISPLAY 0.638298 (-4684 2039);
PAINT MONO (-4684 2039);
FORCEPROP 2 LAST $XR15 81 
J 0
(-4774 2039);
DISPLAY 0.638298 (-4774 2039);
PAINT MONO (-4774 2039);
FORCEPROP 2 LAST $XR16 82 
J 0
(-4864 2039);
DISPLAY 0.638298 (-4864 2039);
PAINT MONO (-4864 2039);
FORCEPROP 2 LAST $XR17 83 
J 0
(-4954 2039);
DISPLAY 0.638298 (-4954 2039);
PAINT MONO (-4954 2039);
FORCEPROP 2 LAST $XR18 84 
J 0
(-5044 2039);
DISPLAY 0.638298 (-5044 2039);
PAINT MONO (-5044 2039);
FORCEPROP 2 LAST $XR19 85 
J 0
(-5134 2039);
DISPLAY 0.638298 (-5134 2039);
PAINT MONO (-5134 2039);
FORCEPROP 2 LAST $XR20 86 
J 0
(-4324 2111);
DISPLAY 0.638298 (-4324 2111);
PAINT MONO (-4324 2111);
FORCEPROP 2 LAST $XR21 87 
J 0
(-4414 2111);
DISPLAY 0.638298 (-4414 2111);
PAINT MONO (-4414 2111);
FORCEPROP 2 LAST $XR22 88 
J 0
(-4504 2111);
DISPLAY 0.638298 (-4504 2111);
PAINT MONO (-4504 2111);
FORCEPROP 2 LAST $XR23 94 
J 0
(-4594 2111);
DISPLAY 0.638298 (-4594 2111);
PAINT MONO (-4594 2111);
FORCEPROP 2 LAST CDS_LIB mstr_standard
J 0
(-4100 2075);
DISPLAY 0.787234 (-4100 2075);
PAINT MONO (-4100 2075);
DISPLAY INVISIBLE (-4100 2075);
FORCEPROP 1 LAST OFFPAGE TRUE
J 0
(-3775 1950);
DISPLAY 1.404255 (-3775 1950);
PAINT GREEN (-3775 1950);
DISPLAY INVISIBLE (-3775 1950);
FORCEPROP 1 LAST COMMENT_BODY TRUE
J 0
(-4000 2000);
DISPLAY 1.404255 (-4000 2000);
PAINT GREEN (-4000 2000);
DISPLAY INVISIBLE (-4000 2000);
FORCEPROP 2 LAST PATH I178
J 0
(-4050 2150);
DISPLAY 0.787234 (-4050 2150);
PAINT ORANGE (-4050 2150);
DISPLAY INVISIBLE (-4050 2150);
FORCEADD OFFPAGE..1
(-3775 2375);
FORCEPROP 2 LAST $XR0 57 
J 0
(-4026 2375);
DISPLAY 0.638298 (-4026 2375);
PAINT MONO (-4026 2375);
FORCEPROP 2 LAST $XR1 78 
J 0
(-4116 2375);
DISPLAY 0.638298 (-4116 2375);
PAINT MONO (-4116 2375);
FORCEPROP 2 LAST CDS_LIB mstr_standard
J 0
(-3775 2375);
DISPLAY 0.787234 (-3775 2375);
PAINT MONO (-3775 2375);
DISPLAY INVISIBLE (-3775 2375);
FORCEPROP 1 LAST OFFPAGE TRUE
J 0
(-3450 2250);
DISPLAY 0.936170 (-3450 2250);
PAINT GREEN (-3450 2250);
DISPLAY INVISIBLE (-3450 2250);
FORCEPROP 1 LAST COMMENT_BODY TRUE
J 0
(-3650 2275);
DISPLAY 0.936170 (-3650 2275);
PAINT GREEN (-3650 2275);
DISPLAY INVISIBLE (-3650 2275);
FORCEPROP 2 LAST PATH I179
J 0
(-4025 2425);
PAINT ORANGE (-4025 2425);
DISPLAY INVISIBLE (-4025 2425);
FORCEADD GND..1
(-4425 825);
FORCEPROP 3 LASTPIN (-4425 875) SIG_NAME GND\g
J 0
(-4415 885);
DISPLAY 0.659574 (-4415 885);
PAINT MONO (-4415 885);
DISPLAY INVISIBLE (-4415 885);
FORCEPROP 1 LAST VOLTAGE 0
J 0
(-4425 825);
PAINT SKYBLUE (-4425 825);
DISPLAY INVISIBLE (-4425 825);
FORCEPROP 1 LAST SIZE 1B
J 0
(-4350 775);
DISPLAY 1.787234 (-4350 775);
PAINT GREEN (-4350 775);
DISPLAY INVISIBLE (-4350 775);
FORCEPROP 2 LAST CDS_LIB mstr_symbols
J 0
(-4425 825);
PAINT ORANGE (-4425 825);
DISPLAY INVISIBLE (-4425 825);
FORCEPROP 2 LAST BOM_COST MEM
J 0
(-4425 830);
PAINT ORANGE (-4425 830);
DISPLAY INVISIBLE (-4425 830);
FORCEPROP 1 LAST BODY_TYPE PLUMBING
J 0
(-4470 782);
DISPLAY 0.340426 (-4470 782);
PAINT GREEN (-4470 782);
DISPLAY INVISIBLE (-4470 782);
FORCEPROP 1 LAST PATH I180
J 0
(-4350 825);
DISPLAY 1.404255 (-4350 825);
PAINT GREEN (-4350 825);
DISPLAY INVISIBLE (-4350 825);
FORCEPROP 2 LAST ROOM DDR4_CH_G
J 0
(-4425 830);
PAINT ORANGE (-4425 830);
DISPLAY INVISIBLE (-4425 830);
FORCEPROP 1 LAST HDL_POWER GND
J 0
(-4425 975);
DISPLAY 1.404255 (-4425 975);
PAINT GREEN (-4425 975);
DISPLAY INVISIBLE (-4425 975);
FORCEADD CAP_A..1
R 2
(-4425 1075);
FORCEPROP 1 LAST LOCATION C1F22
J 2
(-4475 1175);
DISPLAY 0.617021 (-4475 1175);
PAINT AQUA (-4475 1175);
FORCEPROP 1 LAST PART_NUMBER A36096-045
J 2
(-4475 925);
DISPLAY 0.617021 (-4475 925);
PAINT BLUE (-4475 925);
FORCEPROP 1 LAST VALUE 0.01UF
J 2
(-4475 1125);
DISPLAY 0.617021 (-4475 1125);
PAINT SKYBLUE (-4475 1125);
FORCEPROP 1 LAST TOLERANCE 10%
J 2
(-4475 1025);
DISPLAY 0.617021 (-4475 1025);
PAINT SKYBLUE (-4475 1025);
FORCEPROP 1 LAST PACK_TYPE 0402V
J 2
(-4475 875);
DISPLAY 0.617021 (-4475 875);
PAINT SKYBLUE (-4475 875);
FORCEPROP 1 LAST VOLTAGE 25V
J 2
(-4475 1075);
DISPLAY 0.617021 (-4475 1075);
PAINT SKYBLUE (-4475 1075);
FORCEPROP 1 LAST MATERIAL X7R
J 2
(-4475 975);
DISPLAY 0.617021 (-4475 975);
PAINT SKYBLUE (-4475 975);
FORCEPROP 2 LAST CDS_LOCATION C1F22
J 2
(-4475 1175);
DISPLAY 0.617021 (-4475 1175);
PAINT AQUA (-4475 1175);
DISPLAY INVISIBLE (-4475 1175);
FORCEPROP 2 LAST BOM_COST MEM
J 0
(-4425 1075);
PAINT ORANGE (-4425 1075);
DISPLAY INVISIBLE (-4425 1075);
FORCEPROP 2 LAST CDS_LIB dev_discrete
J 0
(-4425 1075);
PAINT ORANGE (-4425 1075);
DISPLAY INVISIBLE (-4425 1075);
FORCEPROP 2 LAST CDS_SEC 1
J 2
(-4475 1275);
PAINT MONO (-4475 1275);
DISPLAY INVISIBLE (-4475 1275);
FORCEPROP 2 LAST $SEC 1
J 0
(-4475 1275);
PAINT MONO (-4475 1275);
DISPLAY INVISIBLE (-4475 1275);
FORCEPROP 1 LAST PATH I181
J 2
(-4475 1225);
DISPLAY 0.978723 (-4475 1225);
PAINT WHITE (-4475 1225);
DISPLAY INVISIBLE (-4475 1225);
FORCEPROP 2 LAST ROOM DDR4_CH_G
J 0
(-4425 1075);
PAINT ORANGE (-4425 1075);
DISPLAY INVISIBLE (-4425 1075);
FORCEPROP 1 LASTPIN (-4425 1175) $PN 1
J 2
(-4435 1155);
DISPLAY 0.787234 (-4435 1155);
PAINT ORANGE (-4435 1155);
DISPLAY INVISIBLE (-4435 1155);
FORCEPROP 1 LASTPIN (-4425 975) $PN 2
J 2
(-4435 955);
DISPLAY 0.787234 (-4435 955);
PAINT ORANGE (-4435 955);
DISPLAY INVISIBLE (-4435 955);
FORCEADD PVPP_GHJ..1
(-1000 2950);
FORCEPROP 3 LASTPIN (-1000 2900) SIG_NAME PVPP_GHJ\g
J 0
(-990 2910);
DISPLAY 0.659574 (-990 2910);
PAINT MONO (-990 2910);
DISPLAY INVISIBLE (-990 2910);
FORCEPROP 1 LAST VOLTAGE 2.5V
J 0
(-1045 2907);
DISPLAY 0.340426 (-1045 2907);
PAINT SKYBLUE (-1045 2907);
DISPLAY INVISIBLE (-1045 2907);
FORCEPROP 0 LAST BOM_COST MEM
J 0
(-1000 3050);
PAINT ORANGE (-1000 3050);
DISPLAY INVISIBLE (-1000 3050);
FORCEPROP 2 LAST CDS_LIB mstr_symbols
J 0
(-1000 2950);
PAINT ORANGE (-1000 2950);
DISPLAY INVISIBLE (-1000 2950);
FORCEPROP 1 LAST BODY_TYPE PLUMBING
J 0
(-1045 2907);
DISPLAY 0.340426 (-1045 2907);
PAINT GREEN (-1045 2907);
DISPLAY INVISIBLE (-1045 2907);
FORCEPROP 1 LAST PATH I182
J 0
(-950 2975);
DISPLAY 0.872340 (-950 2975);
PAINT AQUA (-950 2975);
DISPLAY INVISIBLE (-950 2975);
FORCEPROP 2 LAST ROOM DDR4_CH_G
J 0
(-1000 3050);
PAINT ORANGE (-1000 3050);
DISPLAY INVISIBLE (-1000 3050);
FORCEPROP 1 LAST HDL_POWER PVPP_GHJ
J 1
(-1000 3000);
DISPLAY 0.872340 (-1000 3000);
PAINT GREEN (-1000 3000);
DISPLAY INVISIBLE (-1000 3000);
FORCEADD PVPP_GHJ..1
(-5075 1775);
FORCEPROP 3 LASTPIN (-5075 1725) SIG_NAME PVPP_GHJ\g
J 0
(-5065 1735);
DISPLAY 0.659574 (-5065 1735);
PAINT MONO (-5065 1735);
DISPLAY INVISIBLE (-5065 1735);
FORCEPROP 1 LAST VOLTAGE 2.5V
J 0
(-5120 1732);
DISPLAY 0.340426 (-5120 1732);
PAINT SKYBLUE (-5120 1732);
DISPLAY INVISIBLE (-5120 1732);
FORCEPROP 0 LAST BOM_COST MEM
J 0
(-5075 1875);
PAINT ORANGE (-5075 1875);
DISPLAY INVISIBLE (-5075 1875);
FORCEPROP 2 LAST CDS_LIB mstr_symbols
J 0
(-5075 1775);
PAINT ORANGE (-5075 1775);
DISPLAY INVISIBLE (-5075 1775);
FORCEPROP 1 LAST BODY_TYPE PLUMBING
J 0
(-5120 1732);
DISPLAY 0.340426 (-5120 1732);
PAINT GREEN (-5120 1732);
DISPLAY INVISIBLE (-5120 1732);
FORCEPROP 1 LAST PATH I183
J 0
(-5025 1800);
DISPLAY 0.872340 (-5025 1800);
PAINT AQUA (-5025 1800);
DISPLAY INVISIBLE (-5025 1800);
FORCEPROP 2 LAST ROOM DDR4_CH_H
J 0
(-5075 1875);
PAINT ORANGE (-5075 1875);
DISPLAY INVISIBLE (-5075 1875);
FORCEPROP 1 LAST HDL_POWER PVPP_GHJ
J 1
(-5075 1825);
DISPLAY 0.872340 (-5075 1825);
PAINT GREEN (-5075 1825);
DISPLAY INVISIBLE (-5075 1825);
FORCEADD OFFPAGE..1
(-3775 975);
FORCEPROP 2 LAST $XR0 89 
J 0
(-3996 975);
DISPLAY 0.638298 (-3996 975);
PAINT MONO (-3996 975);
FORCEPROP 2 LAST $XR1 78 
J 0
(-4086 975);
DISPLAY 0.638298 (-4086 975);
PAINT MONO (-4086 975);
FORCEPROP 2 LAST $XR2 79 
J 0
(-4176 975);
DISPLAY 0.638298 (-4176 975);
PAINT MONO (-4176 975);
FORCEPROP 2 LAST $XR3 80 
J 0
(-4266 975);
DISPLAY 0.638298 (-4266 975);
PAINT MONO (-4266 975);
FORCEPROP 2 LAST $XR4 81 
J 0
(-4356 975);
DISPLAY 0.638298 (-4356 975);
PAINT MONO (-4356 975);
FORCEPROP 2 LAST $XR5 82 
J 0
(-3996 939);
DISPLAY 0.638298 (-3996 939);
PAINT MONO (-3996 939);
FORCEPROP 2 LAST CDS_LIB mstr_standard
J 0
(-3775 975);
PAINT ORANGE (-3775 975);
DISPLAY INVISIBLE (-3775 975);
FORCEPROP 1 LAST OFFPAGE TRUE
J 0
(-3450 850);
DISPLAY 0.936170 (-3450 850);
PAINT GREEN (-3450 850);
DISPLAY INVISIBLE (-3450 850);
FORCEPROP 1 LAST COMMENT_BODY TRUE
J 0
(-3650 875);
DISPLAY 0.936170 (-3650 875);
PAINT GREEN (-3650 875);
DISPLAY INVISIBLE (-3650 875);
FORCEPROP 2 LAST PATH I184
J 0
(-3725 1050);
PAINT ORANGE (-3725 1050);
DISPLAY INVISIBLE (-3725 1050);
FORCEADD TAP..6
R 2
(900 4400);
FORCEPROP 3 LASTPIN (850 4400) SIG_NAME M_G_DQS_DN<11>
J 0
(860 4410);
DISPLAY 0.659574 (860 4410);
PAINT MONO (860 4410);
DISPLAY INVISIBLE (860 4410);
FORCEPROP 1 LASTPIN (850 4400) BN 11
J 2
(900 4410);
DISPLAY 0.617021 (900 4410);
PAINT PINK (900 4410);
FORCEPROP 2 LAST CDS_LIB mstr_standard
J 0
(900 4400);
DISPLAY 0.787234 (900 4400);
PAINT MONO (900 4400);
DISPLAY INVISIBLE (900 4400);
FORCEPROP 1 LAST BODY_TYPE PLUMBING
J 2
(900 4350);
DISPLAY 1.234043 (900 4350);
PAINT GREEN (900 4350);
DISPLAY INVISIBLE (900 4350);
FORCEPROP 1 LAST HDL_TAP TRUE
J 2
(575 4275);
DISPLAY 1.234043 (575 4275);
PAINT GREEN (575 4275);
DISPLAY INVISIBLE (575 4275);
FORCEPROP 1 LAST PATH I19
J 2
(900 4400);
DISPLAY 0.936170 (900 4400);
PAINT GREEN (900 4400);
DISPLAY INVISIBLE (900 4400);
FORCEADD P12V_NVDIMM_GHJ..1
(400 2925);
FORCEPROP 3 LASTPIN (400 2875) SIG_NAME P12V_NVDIMM_GHJ\g
J 0
(410 2885);
DISPLAY 0.659574 (410 2885);
PAINT MONO (410 2885);
DISPLAY INVISIBLE (410 2885);
FORCEPROP 1 LAST VOLTAGE 12.0
J 0
(355 2882);
DISPLAY 0.340426 (355 2882);
PAINT SKYBLUE (355 2882);
DISPLAY INVISIBLE (355 2882);
FORCEPROP 2 LAST CDS_LIB mstr_symbols
J 0
(400 2925);
PAINT ORANGE (400 2925);
DISPLAY INVISIBLE (400 2925);
FORCEPROP 1 LAST BODY_TYPE PLUMBING
J 0
(355 2882);
DISPLAY 0.340426 (355 2882);
PAINT GREEN (355 2882);
DISPLAY INVISIBLE (355 2882);
FORCEPROP 1 LAST PATH I197
J 0
(450 2950);
DISPLAY 0.872340 (450 2950);
PAINT AQUA (450 2950);
DISPLAY INVISIBLE (450 2950);
FORCEPROP 1 LAST HDL_POWER P12V_NVDIMM_GHJ
J 1
(400 2975);
DISPLAY 0.872340 (400 2975);
PAINT GREEN (400 2975);
DISPLAY INVISIBLE (400 2975);
FORCEADD OFFPAGE..3
(1600 5050);
FORCEPROP 2 LAST $XR0 57 
J 0
(1814 5050);
DISPLAY 0.638298 (1814 5050);
PAINT MONO (1814 5050);
FORCEPROP 2 LAST $XR1 78 
J 0
(1904 5050);
DISPLAY 0.638298 (1904 5050);
PAINT MONO (1904 5050);
FORCEPROP 2 LAST CDS_LIB mstr_standard
J 0
(1600 5050);
DISPLAY 0.787234 (1600 5050);
PAINT MONO (1600 5050);
DISPLAY INVISIBLE (1600 5050);
FORCEPROP 1 LAST OFFPAGE TRUE
J 0
(1925 4925);
DISPLAY 0.936170 (1925 4925);
PAINT GREEN (1925 4925);
DISPLAY INVISIBLE (1925 4925);
FORCEPROP 1 LAST COMMENT_BODY TRUE
J 0
(1550 4950);
DISPLAY 0.936170 (1550 4950);
PAINT GREEN (1550 4950);
DISPLAY INVISIBLE (1550 4950);
FORCEPROP 2 LAST PATH I2
J 0
(1800 5125);
DISPLAY 0.787234 (1800 5125);
PAINT MONO (1800 5125);
DISPLAY INVISIBLE (1800 5125);
FORCEADD TAP..6
R 2
(900 4200);
FORCEPROP 3 LASTPIN (850 4200) SIG_NAME M_G_DQS_DN<9>
J 0
(860 4210);
DISPLAY 0.659574 (860 4210);
PAINT MONO (860 4210);
DISPLAY INVISIBLE (860 4210);
FORCEPROP 1 LASTPIN (850 4200) BN 9
J 2
(900 4210);
DISPLAY 0.617021 (900 4210);
PAINT PINK (900 4210);
FORCEPROP 2 LAST CDS_LIB mstr_standard
J 0
(900 4200);
DISPLAY 0.787234 (900 4200);
PAINT MONO (900 4200);
DISPLAY INVISIBLE (900 4200);
FORCEPROP 1 LAST BODY_TYPE PLUMBING
J 2
(900 4150);
DISPLAY 1.234043 (900 4150);
PAINT GREEN (900 4150);
DISPLAY INVISIBLE (900 4150);
FORCEPROP 1 LAST HDL_TAP TRUE
J 2
(575 4075);
DISPLAY 1.234043 (575 4075);
PAINT GREEN (575 4075);
DISPLAY INVISIBLE (575 4075);
FORCEPROP 1 LAST PATH I20
J 2
(900 4200);
DISPLAY 0.936170 (900 4200);
PAINT GREEN (900 4200);
DISPLAY INVISIBLE (900 4200);
FORCEADD TAP..6
R 2
(900 4300);
FORCEPROP 3 LASTPIN (850 4300) SIG_NAME M_G_DQS_DN<10>
J 0
(860 4310);
DISPLAY 0.659574 (860 4310);
PAINT MONO (860 4310);
DISPLAY INVISIBLE (860 4310);
FORCEPROP 1 LASTPIN (850 4300) BN 10
J 2
(900 4310);
DISPLAY 0.617021 (900 4310);
PAINT PINK (900 4310);
FORCEPROP 2 LAST CDS_LIB mstr_standard
J 0
(900 4300);
DISPLAY 0.787234 (900 4300);
PAINT MONO (900 4300);
DISPLAY INVISIBLE (900 4300);
FORCEPROP 1 LAST BODY_TYPE PLUMBING
J 2
(900 4250);
DISPLAY 1.234043 (900 4250);
PAINT GREEN (900 4250);
DISPLAY INVISIBLE (900 4250);
FORCEPROP 1 LAST HDL_TAP TRUE
J 2
(575 4175);
DISPLAY 1.234043 (575 4175);
PAINT GREEN (575 4175);
DISPLAY INVISIBLE (575 4175);
FORCEPROP 1 LAST PATH I21
J 2
(900 4300);
DISPLAY 0.936170 (900 4300);
PAINT GREEN (900 4300);
DISPLAY INVISIBLE (900 4300);
FORCEADD TAP..6
R 2
(900 4100);
FORCEPROP 3 LASTPIN (850 4100) SIG_NAME M_G_DQS_DN<8>
J 0
(860 4110);
DISPLAY 0.659574 (860 4110);
PAINT MONO (860 4110);
DISPLAY INVISIBLE (860 4110);
FORCEPROP 1 LASTPIN (850 4100) BN 8
J 2
(900 4110);
DISPLAY 0.617021 (900 4110);
PAINT PINK (900 4110);
FORCEPROP 2 LAST CDS_LIB mstr_standard
J 0
(900 4100);
DISPLAY 0.787234 (900 4100);
PAINT MONO (900 4100);
DISPLAY INVISIBLE (900 4100);
FORCEPROP 1 LAST BODY_TYPE PLUMBING
J 2
(900 4050);
DISPLAY 1.234043 (900 4050);
PAINT GREEN (900 4050);
DISPLAY INVISIBLE (900 4050);
FORCEPROP 1 LAST HDL_TAP TRUE
J 2
(575 3975);
DISPLAY 1.234043 (575 3975);
PAINT GREEN (575 3975);
DISPLAY INVISIBLE (575 3975);
FORCEPROP 1 LAST PATH I22
J 2
(900 4100);
DISPLAY 0.936170 (900 4100);
PAINT GREEN (900 4100);
DISPLAY INVISIBLE (900 4100);
FORCEADD TAP..6
R 2
(900 4000);
FORCEPROP 3 LASTPIN (850 4000) SIG_NAME M_G_DQS_DN<7>
J 0
(860 4010);
DISPLAY 0.659574 (860 4010);
PAINT MONO (860 4010);
DISPLAY INVISIBLE (860 4010);
FORCEPROP 1 LASTPIN (850 4000) BN 7
J 2
(900 4010);
DISPLAY 0.617021 (900 4010);
PAINT PINK (900 4010);
FORCEPROP 2 LAST CDS_LIB mstr_standard
J 0
(900 4000);
DISPLAY 0.787234 (900 4000);
PAINT MONO (900 4000);
DISPLAY INVISIBLE (900 4000);
FORCEPROP 1 LAST BODY_TYPE PLUMBING
J 2
(900 3950);
DISPLAY 1.234043 (900 3950);
PAINT GREEN (900 3950);
DISPLAY INVISIBLE (900 3950);
FORCEPROP 1 LAST HDL_TAP TRUE
J 2
(575 3875);
DISPLAY 1.234043 (575 3875);
PAINT GREEN (575 3875);
DISPLAY INVISIBLE (575 3875);
FORCEPROP 1 LAST PATH I23
J 2
(900 4000);
DISPLAY 0.936170 (900 4000);
PAINT GREEN (900 4000);
DISPLAY INVISIBLE (900 4000);
FORCEADD TAP..6
R 2
(700 4350);
FORCEPROP 3 LASTPIN (650 4350) SIG_NAME M_G_DQS_DP<10>
J 0
(660 4360);
DISPLAY 0.659574 (660 4360);
PAINT MONO (660 4360);
DISPLAY INVISIBLE (660 4360);
FORCEPROP 1 LASTPIN (650 4350) BN 10
J 2
(700 4360);
DISPLAY 0.617021 (700 4360);
PAINT PINK (700 4360);
FORCEPROP 2 LAST CDS_LIB mstr_standard
J 0
(700 4350);
DISPLAY 0.787234 (700 4350);
PAINT MONO (700 4350);
DISPLAY INVISIBLE (700 4350);
FORCEPROP 1 LAST BODY_TYPE PLUMBING
J 2
(700 4300);
DISPLAY 1.234043 (700 4300);
PAINT GREEN (700 4300);
DISPLAY INVISIBLE (700 4300);
FORCEPROP 1 LAST HDL_TAP TRUE
J 2
(375 4225);
DISPLAY 1.234043 (375 4225);
PAINT GREEN (375 4225);
DISPLAY INVISIBLE (375 4225);
FORCEPROP 1 LAST PATH I24
J 2
(700 4350);
DISPLAY 0.936170 (700 4350);
PAINT GREEN (700 4350);
DISPLAY INVISIBLE (700 4350);
FORCEADD TAP..6
R 2
(700 4250);
FORCEPROP 3 LASTPIN (650 4250) SIG_NAME M_G_DQS_DP<9>
J 0
(660 4260);
DISPLAY 0.659574 (660 4260);
PAINT MONO (660 4260);
DISPLAY INVISIBLE (660 4260);
FORCEPROP 1 LASTPIN (650 4250) BN 9
J 2
(700 4260);
DISPLAY 0.617021 (700 4260);
PAINT PINK (700 4260);
FORCEPROP 2 LAST CDS_LIB mstr_standard
J 0
(700 4250);
DISPLAY 0.787234 (700 4250);
PAINT MONO (700 4250);
DISPLAY INVISIBLE (700 4250);
FORCEPROP 1 LAST BODY_TYPE PLUMBING
J 2
(700 4200);
DISPLAY 1.234043 (700 4200);
PAINT GREEN (700 4200);
DISPLAY INVISIBLE (700 4200);
FORCEPROP 1 LAST HDL_TAP TRUE
J 2
(375 4125);
DISPLAY 1.234043 (375 4125);
PAINT GREEN (375 4125);
DISPLAY INVISIBLE (375 4125);
FORCEPROP 1 LAST PATH I25
J 2
(700 4250);
DISPLAY 0.936170 (700 4250);
PAINT GREEN (700 4250);
DISPLAY INVISIBLE (700 4250);
FORCEADD TAP..6
R 2
(700 3950);
FORCEPROP 3 LASTPIN (650 3950) SIG_NAME M_G_DQS_DP<6>
J 0
(660 3960);
DISPLAY 0.659574 (660 3960);
PAINT MONO (660 3960);
DISPLAY INVISIBLE (660 3960);
FORCEPROP 1 LASTPIN (650 3950) BN 6
J 2
(700 3960);
DISPLAY 0.617021 (700 3960);
PAINT PINK (700 3960);
FORCEPROP 2 LAST CDS_LIB mstr_standard
J 0
(700 3950);
DISPLAY 0.787234 (700 3950);
PAINT MONO (700 3950);
DISPLAY INVISIBLE (700 3950);
FORCEPROP 1 LAST BODY_TYPE PLUMBING
J 2
(700 3900);
DISPLAY 1.234043 (700 3900);
PAINT GREEN (700 3900);
DISPLAY INVISIBLE (700 3900);
FORCEPROP 1 LAST HDL_TAP TRUE
J 2
(375 3825);
DISPLAY 1.234043 (375 3825);
PAINT GREEN (375 3825);
DISPLAY INVISIBLE (375 3825);
FORCEPROP 1 LAST PATH I26
J 2
(700 3950);
DISPLAY 0.936170 (700 3950);
PAINT GREEN (700 3950);
DISPLAY INVISIBLE (700 3950);
FORCEADD TAP..6
R 2
(700 4050);
FORCEPROP 3 LASTPIN (650 4050) SIG_NAME M_G_DQS_DP<7>
J 0
(660 4060);
DISPLAY 0.659574 (660 4060);
PAINT MONO (660 4060);
DISPLAY INVISIBLE (660 4060);
FORCEPROP 1 LASTPIN (650 4050) BN 7
J 2
(700 4060);
DISPLAY 0.617021 (700 4060);
PAINT PINK (700 4060);
FORCEPROP 2 LAST CDS_LIB mstr_standard
J 0
(700 4050);
DISPLAY 0.787234 (700 4050);
PAINT MONO (700 4050);
DISPLAY INVISIBLE (700 4050);
FORCEPROP 1 LAST BODY_TYPE PLUMBING
J 2
(700 4000);
DISPLAY 1.234043 (700 4000);
PAINT GREEN (700 4000);
DISPLAY INVISIBLE (700 4000);
FORCEPROP 1 LAST HDL_TAP TRUE
J 2
(375 3925);
DISPLAY 1.234043 (375 3925);
PAINT GREEN (375 3925);
DISPLAY INVISIBLE (375 3925);
FORCEPROP 1 LAST PATH I27
J 2
(700 4050);
DISPLAY 0.936170 (700 4050);
PAINT GREEN (700 4050);
DISPLAY INVISIBLE (700 4050);
FORCEADD TAP..6
R 2
(700 4150);
FORCEPROP 3 LASTPIN (650 4150) SIG_NAME M_G_DQS_DP<8>
J 0
(660 4160);
DISPLAY 0.659574 (660 4160);
PAINT MONO (660 4160);
DISPLAY INVISIBLE (660 4160);
FORCEPROP 1 LASTPIN (650 4150) BN 8
J 2
(700 4160);
DISPLAY 0.617021 (700 4160);
PAINT PINK (700 4160);
FORCEPROP 2 LAST CDS_LIB mstr_standard
J 0
(700 4150);
DISPLAY 0.787234 (700 4150);
PAINT MONO (700 4150);
DISPLAY INVISIBLE (700 4150);
FORCEPROP 1 LAST BODY_TYPE PLUMBING
J 2
(700 4100);
DISPLAY 1.234043 (700 4100);
PAINT GREEN (700 4100);
DISPLAY INVISIBLE (700 4100);
FORCEPROP 1 LAST HDL_TAP TRUE
J 2
(375 4025);
DISPLAY 1.234043 (375 4025);
PAINT GREEN (375 4025);
DISPLAY INVISIBLE (375 4025);
FORCEPROP 1 LAST PATH I28
J 2
(700 4150);
DISPLAY 0.936170 (700 4150);
PAINT GREEN (700 4150);
DISPLAY INVISIBLE (700 4150);
FORCEADD TAP..6
R 2
(900 3900);
FORCEPROP 3 LASTPIN (850 3900) SIG_NAME M_G_DQS_DN<6>
J 0
(860 3910);
DISPLAY 0.659574 (860 3910);
PAINT MONO (860 3910);
DISPLAY INVISIBLE (860 3910);
FORCEPROP 1 LASTPIN (850 3900) BN 6
J 2
(900 3910);
DISPLAY 0.617021 (900 3910);
PAINT PINK (900 3910);
FORCEPROP 2 LAST CDS_LIB mstr_standard
J 0
(900 3900);
DISPLAY 0.787234 (900 3900);
PAINT MONO (900 3900);
DISPLAY INVISIBLE (900 3900);
FORCEPROP 1 LAST BODY_TYPE PLUMBING
J 2
(900 3850);
DISPLAY 1.234043 (900 3850);
PAINT GREEN (900 3850);
DISPLAY INVISIBLE (900 3850);
FORCEPROP 1 LAST HDL_TAP TRUE
J 2
(575 3775);
DISPLAY 1.234043 (575 3775);
PAINT GREEN (575 3775);
DISPLAY INVISIBLE (575 3775);
FORCEPROP 1 LAST PATH I29
J 2
(900 3900);
DISPLAY 0.936170 (900 3900);
PAINT GREEN (900 3900);
DISPLAY INVISIBLE (900 3900);
FORCEADD TAP..6
R 2
(900 5000);
FORCEPROP 3 LASTPIN (850 5000) SIG_NAME M_G_DQS_DN<17>
J 0
(860 5010);
DISPLAY 0.659574 (860 5010);
PAINT MONO (860 5010);
DISPLAY INVISIBLE (860 5010);
FORCEPROP 1 LASTPIN (850 5000) BN 17
J 2
(900 5010);
DISPLAY 0.617021 (900 5010);
PAINT PINK (900 5010);
FORCEPROP 2 LAST CDS_LIB mstr_standard
J 2
(900 5000);
DISPLAY 0.787234 (900 5000);
PAINT MONO (900 5000);
DISPLAY INVISIBLE (900 5000);
FORCEPROP 1 LAST BODY_TYPE PLUMBING
J 2
(900 4950);
DISPLAY 1.234043 (900 4950);
PAINT GREEN (900 4950);
DISPLAY INVISIBLE (900 4950);
FORCEPROP 1 LAST HDL_TAP TRUE
J 2
(575 4875);
DISPLAY 1.234043 (575 4875);
PAINT GREEN (575 4875);
DISPLAY INVISIBLE (575 4875);
FORCEPROP 1 LAST PATH I3
J 2
(900 5000);
DISPLAY 0.936170 (900 5000);
PAINT GREEN (900 5000);
DISPLAY INVISIBLE (900 5000);
FORCEADD TAP..6
R 2
(900 3700);
FORCEPROP 3 LASTPIN (850 3700) SIG_NAME M_G_DQS_DN<4>
J 0
(860 3710);
DISPLAY 0.659574 (860 3710);
PAINT MONO (860 3710);
DISPLAY INVISIBLE (860 3710);
FORCEPROP 1 LASTPIN (850 3700) BN 4
J 2
(900 3710);
DISPLAY 0.617021 (900 3710);
PAINT PINK (900 3710);
FORCEPROP 2 LAST CDS_LIB mstr_standard
J 0
(900 3700);
DISPLAY 0.787234 (900 3700);
PAINT MONO (900 3700);
DISPLAY INVISIBLE (900 3700);
FORCEPROP 1 LAST BODY_TYPE PLUMBING
J 2
(900 3650);
DISPLAY 1.234043 (900 3650);
PAINT GREEN (900 3650);
DISPLAY INVISIBLE (900 3650);
FORCEPROP 1 LAST HDL_TAP TRUE
J 2
(575 3575);
DISPLAY 1.234043 (575 3575);
PAINT GREEN (575 3575);
DISPLAY INVISIBLE (575 3575);
FORCEPROP 1 LAST PATH I30
J 2
(900 3700);
DISPLAY 0.936170 (900 3700);
PAINT GREEN (900 3700);
DISPLAY INVISIBLE (900 3700);
FORCEADD TAP..6
R 2
(900 3800);
FORCEPROP 3 LASTPIN (850 3800) SIG_NAME M_G_DQS_DN<5>
J 0
(860 3810);
DISPLAY 0.659574 (860 3810);
PAINT MONO (860 3810);
DISPLAY INVISIBLE (860 3810);
FORCEPROP 1 LASTPIN (850 3800) BN 5
J 2
(900 3810);
DISPLAY 0.617021 (900 3810);
PAINT PINK (900 3810);
FORCEPROP 2 LAST CDS_LIB mstr_standard
J 0
(900 3800);
DISPLAY 0.787234 (900 3800);
PAINT MONO (900 3800);
DISPLAY INVISIBLE (900 3800);
FORCEPROP 1 LAST BODY_TYPE PLUMBING
J 2
(900 3750);
DISPLAY 1.234043 (900 3750);
PAINT GREEN (900 3750);
DISPLAY INVISIBLE (900 3750);
FORCEPROP 1 LAST HDL_TAP TRUE
J 2
(575 3675);
DISPLAY 1.234043 (575 3675);
PAINT GREEN (575 3675);
DISPLAY INVISIBLE (575 3675);
FORCEPROP 1 LAST PATH I31
J 2
(900 3800);
DISPLAY 0.936170 (900 3800);
PAINT GREEN (900 3800);
DISPLAY INVISIBLE (900 3800);
FORCEADD TAP..6
R 2
(900 3500);
FORCEPROP 3 LASTPIN (850 3500) SIG_NAME M_G_DQS_DN<2>
J 0
(860 3510);
DISPLAY 0.659574 (860 3510);
PAINT MONO (860 3510);
DISPLAY INVISIBLE (860 3510);
FORCEPROP 1 LASTPIN (850 3500) BN 2
J 2
(900 3510);
DISPLAY 0.617021 (900 3510);
PAINT PINK (900 3510);
FORCEPROP 2 LAST CDS_LIB mstr_standard
J 0
(900 3500);
DISPLAY 0.787234 (900 3500);
PAINT MONO (900 3500);
DISPLAY INVISIBLE (900 3500);
FORCEPROP 1 LAST BODY_TYPE PLUMBING
J 2
(900 3450);
DISPLAY 1.234043 (900 3450);
PAINT GREEN (900 3450);
DISPLAY INVISIBLE (900 3450);
FORCEPROP 1 LAST HDL_TAP TRUE
J 2
(575 3375);
DISPLAY 1.234043 (575 3375);
PAINT GREEN (575 3375);
DISPLAY INVISIBLE (575 3375);
FORCEPROP 1 LAST PATH I32
J 2
(900 3500);
DISPLAY 0.936170 (900 3500);
PAINT GREEN (900 3500);
DISPLAY INVISIBLE (900 3500);
FORCEADD TAP..6
R 2
(900 3600);
FORCEPROP 3 LASTPIN (850 3600) SIG_NAME M_G_DQS_DN<3>
J 0
(860 3610);
DISPLAY 0.659574 (860 3610);
PAINT MONO (860 3610);
DISPLAY INVISIBLE (860 3610);
FORCEPROP 1 LASTPIN (850 3600) BN 3
J 2
(900 3610);
DISPLAY 0.617021 (900 3610);
PAINT PINK (900 3610);
FORCEPROP 2 LAST CDS_LIB mstr_standard
J 0
(900 3600);
DISPLAY 0.787234 (900 3600);
PAINT MONO (900 3600);
DISPLAY INVISIBLE (900 3600);
FORCEPROP 1 LAST BODY_TYPE PLUMBING
J 2
(900 3550);
DISPLAY 1.234043 (900 3550);
PAINT GREEN (900 3550);
DISPLAY INVISIBLE (900 3550);
FORCEPROP 1 LAST HDL_TAP TRUE
J 2
(575 3475);
DISPLAY 1.234043 (575 3475);
PAINT GREEN (575 3475);
DISPLAY INVISIBLE (575 3475);
FORCEPROP 1 LAST PATH I33
J 2
(900 3600);
DISPLAY 0.936170 (900 3600);
PAINT GREEN (900 3600);
DISPLAY INVISIBLE (900 3600);
FORCEADD TAP..6
R 2
(700 3750);
FORCEPROP 3 LASTPIN (650 3750) SIG_NAME M_G_DQS_DP<4>
J 0
(660 3760);
DISPLAY 0.659574 (660 3760);
PAINT MONO (660 3760);
DISPLAY INVISIBLE (660 3760);
FORCEPROP 1 LASTPIN (650 3750) BN 4
J 2
(700 3760);
DISPLAY 0.617021 (700 3760);
PAINT PINK (700 3760);
FORCEPROP 2 LAST CDS_LIB mstr_standard
J 0
(700 3750);
DISPLAY 0.787234 (700 3750);
PAINT MONO (700 3750);
DISPLAY INVISIBLE (700 3750);
FORCEPROP 1 LAST BODY_TYPE PLUMBING
J 2
(700 3700);
DISPLAY 1.234043 (700 3700);
PAINT GREEN (700 3700);
DISPLAY INVISIBLE (700 3700);
FORCEPROP 1 LAST HDL_TAP TRUE
J 2
(375 3625);
DISPLAY 1.234043 (375 3625);
PAINT GREEN (375 3625);
DISPLAY INVISIBLE (375 3625);
FORCEPROP 1 LAST PATH I34
J 2
(700 3750);
DISPLAY 0.936170 (700 3750);
PAINT GREEN (700 3750);
DISPLAY INVISIBLE (700 3750);
FORCEADD TAP..6
R 2
(700 3850);
FORCEPROP 3 LASTPIN (650 3850) SIG_NAME M_G_DQS_DP<5>
J 0
(660 3860);
DISPLAY 0.659574 (660 3860);
PAINT MONO (660 3860);
DISPLAY INVISIBLE (660 3860);
FORCEPROP 1 LASTPIN (650 3850) BN 5
J 2
(700 3860);
DISPLAY 0.617021 (700 3860);
PAINT PINK (700 3860);
FORCEPROP 2 LAST CDS_LIB mstr_standard
J 0
(700 3850);
DISPLAY 0.787234 (700 3850);
PAINT MONO (700 3850);
DISPLAY INVISIBLE (700 3850);
FORCEPROP 1 LAST BODY_TYPE PLUMBING
J 2
(700 3800);
DISPLAY 1.234043 (700 3800);
PAINT GREEN (700 3800);
DISPLAY INVISIBLE (700 3800);
FORCEPROP 1 LAST HDL_TAP TRUE
J 2
(375 3725);
DISPLAY 1.234043 (375 3725);
PAINT GREEN (375 3725);
DISPLAY INVISIBLE (375 3725);
FORCEPROP 1 LAST PATH I35
J 2
(700 3850);
DISPLAY 0.936170 (700 3850);
PAINT GREEN (700 3850);
DISPLAY INVISIBLE (700 3850);
FORCEADD TAP..6
R 2
(700 3550);
FORCEPROP 3 LASTPIN (650 3550) SIG_NAME M_G_DQS_DP<2>
J 0
(660 3560);
DISPLAY 0.659574 (660 3560);
PAINT MONO (660 3560);
DISPLAY INVISIBLE (660 3560);
FORCEPROP 1 LASTPIN (650 3550) BN 2
J 2
(700 3560);
DISPLAY 0.617021 (700 3560);
PAINT PINK (700 3560);
FORCEPROP 2 LAST CDS_LIB mstr_standard
J 0
(700 3550);
DISPLAY 0.787234 (700 3550);
PAINT MONO (700 3550);
DISPLAY INVISIBLE (700 3550);
FORCEPROP 1 LAST BODY_TYPE PLUMBING
J 2
(700 3500);
DISPLAY 1.234043 (700 3500);
PAINT GREEN (700 3500);
DISPLAY INVISIBLE (700 3500);
FORCEPROP 1 LAST HDL_TAP TRUE
J 2
(375 3425);
DISPLAY 1.234043 (375 3425);
PAINT GREEN (375 3425);
DISPLAY INVISIBLE (375 3425);
FORCEPROP 1 LAST PATH I36
J 2
(700 3550);
DISPLAY 0.936170 (700 3550);
PAINT GREEN (700 3550);
DISPLAY INVISIBLE (700 3550);
FORCEADD TAP..6
R 2
(700 3450);
FORCEPROP 3 LASTPIN (650 3450) SIG_NAME M_G_DQS_DP<1>
J 0
(660 3460);
DISPLAY 0.659574 (660 3460);
PAINT MONO (660 3460);
DISPLAY INVISIBLE (660 3460);
FORCEPROP 1 LASTPIN (650 3450) BN 1
J 2
(700 3460);
DISPLAY 0.617021 (700 3460);
PAINT PINK (700 3460);
FORCEPROP 2 LAST CDS_LIB mstr_standard
J 0
(700 3450);
DISPLAY 0.787234 (700 3450);
PAINT MONO (700 3450);
DISPLAY INVISIBLE (700 3450);
FORCEPROP 1 LAST BODY_TYPE PLUMBING
J 2
(700 3400);
DISPLAY 1.234043 (700 3400);
PAINT GREEN (700 3400);
DISPLAY INVISIBLE (700 3400);
FORCEPROP 1 LAST HDL_TAP TRUE
J 2
(375 3325);
DISPLAY 1.234043 (375 3325);
PAINT GREEN (375 3325);
DISPLAY INVISIBLE (375 3325);
FORCEPROP 1 LAST PATH I37
J 2
(700 3450);
DISPLAY 0.936170 (700 3450);
PAINT GREEN (700 3450);
DISPLAY INVISIBLE (700 3450);
FORCEADD TAP..6
R 2
(700 3650);
FORCEPROP 3 LASTPIN (650 3650) SIG_NAME M_G_DQS_DP<3>
J 0
(660 3660);
DISPLAY 0.659574 (660 3660);
PAINT MONO (660 3660);
DISPLAY INVISIBLE (660 3660);
FORCEPROP 1 LASTPIN (650 3650) BN 3
J 2
(700 3660);
DISPLAY 0.617021 (700 3660);
PAINT PINK (700 3660);
FORCEPROP 2 LAST CDS_LIB mstr_standard
J 0
(700 3650);
DISPLAY 0.787234 (700 3650);
PAINT MONO (700 3650);
DISPLAY INVISIBLE (700 3650);
FORCEPROP 1 LAST BODY_TYPE PLUMBING
J 2
(700 3600);
DISPLAY 1.234043 (700 3600);
PAINT GREEN (700 3600);
DISPLAY INVISIBLE (700 3600);
FORCEPROP 1 LAST HDL_TAP TRUE
J 2
(375 3525);
DISPLAY 1.234043 (375 3525);
PAINT GREEN (375 3525);
DISPLAY INVISIBLE (375 3525);
FORCEPROP 1 LAST PATH I38
J 2
(700 3650);
DISPLAY 0.936170 (700 3650);
PAINT GREEN (700 3650);
DISPLAY INVISIBLE (700 3650);
FORCEADD TAP..6
R 2
(900 3300);
FORCEPROP 3 LASTPIN (850 3300) SIG_NAME M_G_DQS_DN<0>
J 0
(860 3310);
DISPLAY 0.659574 (860 3310);
PAINT MONO (860 3310);
DISPLAY INVISIBLE (860 3310);
FORCEPROP 1 LASTPIN (850 3300) BN 0
J 2
(900 3310);
DISPLAY 0.617021 (900 3310);
PAINT PINK (900 3310);
FORCEPROP 2 LAST CDS_LIB mstr_standard
J 0
(900 3300);
DISPLAY 0.787234 (900 3300);
PAINT MONO (900 3300);
DISPLAY INVISIBLE (900 3300);
FORCEPROP 1 LAST BODY_TYPE PLUMBING
J 2
(900 3250);
DISPLAY 1.234043 (900 3250);
PAINT GREEN (900 3250);
DISPLAY INVISIBLE (900 3250);
FORCEPROP 1 LAST HDL_TAP TRUE
J 2
(575 3175);
DISPLAY 1.234043 (575 3175);
PAINT GREEN (575 3175);
DISPLAY INVISIBLE (575 3175);
FORCEPROP 1 LAST PATH I39
J 2
(900 3300);
DISPLAY 0.936170 (900 3300);
PAINT GREEN (900 3300);
DISPLAY INVISIBLE (900 3300);
FORCEADD TAP..6
R 2
(700 5050);
FORCEPROP 3 LASTPIN (650 5050) SIG_NAME M_G_DQS_DP<17>
J 0
(660 5060);
DISPLAY 0.659574 (660 5060);
PAINT MONO (660 5060);
DISPLAY INVISIBLE (660 5060);
FORCEPROP 1 LASTPIN (650 5050) BN 17
J 2
(700 5060);
DISPLAY 0.617021 (700 5060);
PAINT PINK (700 5060);
FORCEPROP 2 LAST CDS_LIB mstr_standard
J 2
(700 5050);
DISPLAY 0.787234 (700 5050);
PAINT MONO (700 5050);
DISPLAY INVISIBLE (700 5050);
FORCEPROP 1 LAST BODY_TYPE PLUMBING
J 2
(700 5000);
DISPLAY 1.234043 (700 5000);
PAINT GREEN (700 5000);
DISPLAY INVISIBLE (700 5000);
FORCEPROP 1 LAST HDL_TAP TRUE
J 2
(375 4925);
DISPLAY 1.234043 (375 4925);
PAINT GREEN (375 4925);
DISPLAY INVISIBLE (375 4925);
FORCEPROP 1 LAST PATH I4
J 2
(700 5050);
DISPLAY 0.936170 (700 5050);
PAINT GREEN (700 5050);
DISPLAY INVISIBLE (700 5050);
FORCEADD TAP..6
R 2
(900 3400);
FORCEPROP 3 LASTPIN (850 3400) SIG_NAME M_G_DQS_DN<1>
J 0
(860 3410);
DISPLAY 0.659574 (860 3410);
PAINT MONO (860 3410);
DISPLAY INVISIBLE (860 3410);
FORCEPROP 1 LASTPIN (850 3400) BN 1
J 2
(900 3410);
DISPLAY 0.617021 (900 3410);
PAINT PINK (900 3410);
FORCEPROP 2 LAST CDS_LIB mstr_standard
J 0
(900 3400);
DISPLAY 0.787234 (900 3400);
PAINT MONO (900 3400);
DISPLAY INVISIBLE (900 3400);
FORCEPROP 1 LAST BODY_TYPE PLUMBING
J 2
(900 3350);
DISPLAY 1.234043 (900 3350);
PAINT GREEN (900 3350);
DISPLAY INVISIBLE (900 3350);
FORCEPROP 1 LAST HDL_TAP TRUE
J 2
(575 3275);
DISPLAY 1.234043 (575 3275);
PAINT GREEN (575 3275);
DISPLAY INVISIBLE (575 3275);
FORCEPROP 1 LAST PATH I40
J 2
(900 3400);
DISPLAY 0.936170 (900 3400);
PAINT GREEN (900 3400);
DISPLAY INVISIBLE (900 3400);
FORCEADD TAP..6
R 2
(700 3350);
FORCEPROP 3 LASTPIN (650 3350) SIG_NAME M_G_DQS_DP<0>
J 0
(660 3360);
DISPLAY 0.659574 (660 3360);
PAINT MONO (660 3360);
DISPLAY INVISIBLE (660 3360);
FORCEPROP 1 LASTPIN (650 3350) BN 0
J 2
(700 3360);
DISPLAY 0.617021 (700 3360);
PAINT PINK (700 3360);
FORCEPROP 2 LAST CDS_LIB mstr_standard
J 0
(700 3350);
DISPLAY 0.787234 (700 3350);
PAINT MONO (700 3350);
DISPLAY INVISIBLE (700 3350);
FORCEPROP 1 LAST BODY_TYPE PLUMBING
J 2
(700 3300);
DISPLAY 1.234043 (700 3300);
PAINT GREEN (700 3300);
DISPLAY INVISIBLE (700 3300);
FORCEPROP 1 LAST HDL_TAP TRUE
J 2
(375 3225);
DISPLAY 1.234043 (375 3225);
PAINT GREEN (375 3225);
DISPLAY INVISIBLE (375 3225);
FORCEPROP 1 LAST PATH I41
J 2
(700 3350);
DISPLAY 0.936170 (700 3350);
PAINT GREEN (700 3350);
DISPLAY INVISIBLE (700 3350);
FORCEADD SCONN288_H44441004..3
(1800 2200);
FORCEPROP 1 LAST LOCATION J1G1
J 0
(1350 3600);
DISPLAY 0.617021 (1350 3600);
PAINT AQUA (1350 3600);
FORCEPROP 1 LAST PART_NUMBER H44441-004
J 0
(1350 850);
DISPLAY 0.617021 (1350 850);
PAINT BLUE (1350 850);
FORCEPROP 1 LAST MATERIAL SCONN
J 0
(1350 3550);
DISPLAY 0.617021 (1350 3550);
PAINT SKYBLUE (1350 3550);
FORCEPROP 2 LASTPIN (1300 3350) $PN 2
J 2
(1290 3360);
DISPLAY 0.617021 (1290 3360);
PAINT ORANGE (1290 3360);
FORCEPROP 2 LASTPIN (1300 3300) $PN 4
J 2
(1290 3310);
DISPLAY 0.617021 (1290 3310);
PAINT ORANGE (1290 3310);
FORCEPROP 2 LASTPIN (1300 3250) $PN 6
J 2
(1290 3260);
DISPLAY 0.617021 (1290 3260);
PAINT ORANGE (1290 3260);
FORCEPROP 2 LASTPIN (1300 3200) $PN 9
J 2
(1290 3210);
DISPLAY 0.617021 (1290 3210);
PAINT ORANGE (1290 3210);
FORCEPROP 2 LASTPIN (1300 3150) $PN 11
J 2
(1290 3160);
DISPLAY 0.617021 (1290 3160);
PAINT ORANGE (1290 3160);
FORCEPROP 2 LASTPIN (1300 3100) $PN 13
J 2
(1290 3110);
DISPLAY 0.617021 (1290 3110);
PAINT ORANGE (1290 3110);
FORCEPROP 2 LASTPIN (1300 3050) $PN 15
J 2
(1290 3060);
DISPLAY 0.617021 (1290 3060);
PAINT ORANGE (1290 3060);
FORCEPROP 2 LASTPIN (1300 3000) $PN 17
J 2
(1290 3010);
DISPLAY 0.617021 (1290 3010);
PAINT ORANGE (1290 3010);
FORCEPROP 2 LASTPIN (1300 2950) $PN 20
J 2
(1290 2960);
DISPLAY 0.617021 (1290 2960);
PAINT ORANGE (1290 2960);
FORCEPROP 2 LASTPIN (1300 2900) $PN 22
J 2
(1290 2910);
DISPLAY 0.617021 (1290 2910);
PAINT ORANGE (1290 2910);
FORCEPROP 2 LASTPIN (1300 2850) $PN 24
J 2
(1290 2860);
DISPLAY 0.617021 (1290 2860);
PAINT ORANGE (1290 2860);
FORCEPROP 2 LASTPIN (1300 2800) $PN 26
J 2
(1290 2810);
DISPLAY 0.617021 (1290 2810);
PAINT ORANGE (1290 2810);
FORCEPROP 2 LASTPIN (1300 2750) $PN 28
J 2
(1290 2760);
DISPLAY 0.617021 (1290 2760);
PAINT ORANGE (1290 2760);
FORCEPROP 2 LASTPIN (1300 2700) $PN 31
J 2
(1290 2710);
DISPLAY 0.617021 (1290 2710);
PAINT ORANGE (1290 2710);
FORCEPROP 2 LASTPIN (1300 2650) $PN 33
J 2
(1290 2660);
DISPLAY 0.617021 (1290 2660);
PAINT ORANGE (1290 2660);
FORCEPROP 2 LASTPIN (1300 2600) $PN 35
J 2
(1290 2610);
DISPLAY 0.617021 (1290 2610);
PAINT ORANGE (1290 2610);
FORCEPROP 2 LASTPIN (1300 2550) $PN 37
J 2
(1290 2560);
DISPLAY 0.617021 (1290 2560);
PAINT ORANGE (1290 2560);
FORCEPROP 2 LASTPIN (1300 2500) $PN 39
J 2
(1290 2510);
DISPLAY 0.617021 (1290 2510);
PAINT ORANGE (1290 2510);
FORCEPROP 2 LASTPIN (1300 2450) $PN 42
J 2
(1290 2460);
DISPLAY 0.617021 (1290 2460);
PAINT ORANGE (1290 2460);
FORCEPROP 2 LASTPIN (1300 2400) $PN 44
J 2
(1290 2410);
DISPLAY 0.617021 (1290 2410);
PAINT ORANGE (1290 2410);
FORCEPROP 2 LASTPIN (1300 2350) $PN 46
J 2
(1290 2360);
DISPLAY 0.617021 (1290 2360);
PAINT ORANGE (1290 2360);
FORCEPROP 2 LASTPIN (1300 2300) $PN 48
J 2
(1290 2310);
DISPLAY 0.617021 (1290 2310);
PAINT ORANGE (1290 2310);
FORCEPROP 2 LASTPIN (1300 2250) $PN 50
J 2
(1290 2260);
DISPLAY 0.617021 (1290 2260);
PAINT ORANGE (1290 2260);
FORCEPROP 2 LASTPIN (1300 2200) $PN 53
J 2
(1290 2210);
DISPLAY 0.617021 (1290 2210);
PAINT ORANGE (1290 2210);
FORCEPROP 2 LASTPIN (1300 2150) $PN 55
J 2
(1290 2160);
DISPLAY 0.617021 (1290 2160);
PAINT ORANGE (1290 2160);
FORCEPROP 2 LASTPIN (1300 2100) $PN 57
J 2
(1290 2110);
DISPLAY 0.617021 (1290 2110);
PAINT ORANGE (1290 2110);
FORCEPROP 2 LASTPIN (1300 2050) $PN 94
J 2
(1290 2060);
DISPLAY 0.617021 (1290 2060);
PAINT ORANGE (1290 2060);
FORCEPROP 2 LASTPIN (1300 2000) $PN 96
J 2
(1290 2010);
DISPLAY 0.617021 (1290 2010);
PAINT ORANGE (1290 2010);
FORCEPROP 2 LASTPIN (1300 1950) $PN 98
J 2
(1290 1960);
DISPLAY 0.617021 (1290 1960);
PAINT ORANGE (1290 1960);
FORCEPROP 2 LASTPIN (1300 1900) $PN 101
J 2
(1290 1910);
DISPLAY 0.617021 (1290 1910);
PAINT ORANGE (1290 1910);
FORCEPROP 2 LASTPIN (1300 1850) $PN 103
J 2
(1290 1860);
DISPLAY 0.617021 (1290 1860);
PAINT ORANGE (1290 1860);
FORCEPROP 2 LASTPIN (1300 1800) $PN 105
J 2
(1290 1810);
DISPLAY 0.617021 (1290 1810);
PAINT ORANGE (1290 1810);
FORCEPROP 2 LASTPIN (1300 1750) $PN 107
J 2
(1290 1760);
DISPLAY 0.617021 (1290 1760);
PAINT ORANGE (1290 1760);
FORCEPROP 2 LASTPIN (1300 1700) $PN 109
J 2
(1290 1710);
DISPLAY 0.617021 (1290 1710);
PAINT ORANGE (1290 1710);
FORCEPROP 2 LASTPIN (1300 1650) $PN 112
J 2
(1290 1660);
DISPLAY 0.617021 (1290 1660);
PAINT ORANGE (1290 1660);
FORCEPROP 2 LASTPIN (1300 1600) $PN 114
J 2
(1290 1610);
DISPLAY 0.617021 (1290 1610);
PAINT ORANGE (1290 1610);
FORCEPROP 2 LASTPIN (1300 1550) $PN 116
J 2
(1290 1560);
DISPLAY 0.617021 (1290 1560);
PAINT ORANGE (1290 1560);
FORCEPROP 2 LASTPIN (1300 1500) $PN 118
J 2
(1290 1510);
DISPLAY 0.617021 (1290 1510);
PAINT ORANGE (1290 1510);
FORCEPROP 2 LASTPIN (1300 1450) $PN 120
J 2
(1290 1460);
DISPLAY 0.617021 (1290 1460);
PAINT ORANGE (1290 1460);
FORCEPROP 2 LASTPIN (1300 1400) $PN 123
J 2
(1290 1410);
DISPLAY 0.617021 (1290 1410);
PAINT ORANGE (1290 1410);
FORCEPROP 2 LASTPIN (1300 1350) $PN 125
J 2
(1290 1360);
DISPLAY 0.617021 (1290 1360);
PAINT ORANGE (1290 1360);
FORCEPROP 2 LASTPIN (1300 1300) $PN 127
J 2
(1290 1310);
DISPLAY 0.617021 (1290 1310);
PAINT ORANGE (1290 1310);
FORCEPROP 2 LASTPIN (1300 1250) $PN 129
J 2
(1290 1260);
DISPLAY 0.617021 (1290 1260);
PAINT ORANGE (1290 1260);
FORCEPROP 2 LASTPIN (1300 1200) $PN 131
J 2
(1290 1210);
DISPLAY 0.617021 (1290 1210);
PAINT ORANGE (1290 1210);
FORCEPROP 2 LASTPIN (1300 1150) $PN 134
J 2
(1290 1160);
DISPLAY 0.617021 (1290 1160);
PAINT ORANGE (1290 1160);
FORCEPROP 2 LASTPIN (1300 1100) $PN 136
J 2
(1290 1110);
DISPLAY 0.617021 (1290 1110);
PAINT ORANGE (1290 1110);
FORCEPROP 2 LASTPIN (1300 1050) $PN 138
J 2
(1290 1060);
DISPLAY 0.617021 (1290 1060);
PAINT ORANGE (1290 1060);
FORCEPROP 2 LASTPIN (2300 3350) $PN 147
J 0
(2310 3360);
DISPLAY 0.617021 (2310 3360);
PAINT ORANGE (2310 3360);
FORCEPROP 2 LASTPIN (2300 3300) $PN 149
J 0
(2310 3310);
DISPLAY 0.617021 (2310 3310);
PAINT ORANGE (2310 3310);
FORCEPROP 2 LASTPIN (2300 3250) $PN 151
J 0
(2310 3260);
DISPLAY 0.617021 (2310 3260);
PAINT ORANGE (2310 3260);
FORCEPROP 2 LASTPIN (2300 3200) $PN 154
J 0
(2310 3210);
DISPLAY 0.617021 (2310 3210);
PAINT ORANGE (2310 3210);
FORCEPROP 2 LASTPIN (2300 3150) $PN 156
J 0
(2310 3160);
DISPLAY 0.617021 (2310 3160);
PAINT ORANGE (2310 3160);
FORCEPROP 2 LASTPIN (2300 3100) $PN 158
J 0
(2310 3110);
DISPLAY 0.617021 (2310 3110);
PAINT ORANGE (2310 3110);
FORCEPROP 2 LASTPIN (2300 3050) $PN 160
J 0
(2310 3060);
DISPLAY 0.617021 (2310 3060);
PAINT ORANGE (2310 3060);
FORCEPROP 2 LASTPIN (2300 3000) $PN 162
J 0
(2310 3010);
DISPLAY 0.617021 (2310 3010);
PAINT ORANGE (2310 3010);
FORCEPROP 2 LASTPIN (2300 2950) $PN 165
J 0
(2310 2960);
DISPLAY 0.617021 (2310 2960);
PAINT ORANGE (2310 2960);
FORCEPROP 2 LASTPIN (2300 2900) $PN 167
J 0
(2310 2910);
DISPLAY 0.617021 (2310 2910);
PAINT ORANGE (2310 2910);
FORCEPROP 2 LASTPIN (2300 2850) $PN 169
J 0
(2310 2860);
DISPLAY 0.617021 (2310 2860);
PAINT ORANGE (2310 2860);
FORCEPROP 2 LASTPIN (2300 2800) $PN 171
J 0
(2310 2810);
DISPLAY 0.617021 (2310 2810);
PAINT ORANGE (2310 2810);
FORCEPROP 2 LASTPIN (2300 2750) $PN 173
J 0
(2310 2760);
DISPLAY 0.617021 (2310 2760);
PAINT ORANGE (2310 2760);
FORCEPROP 2 LASTPIN (2300 2700) $PN 176
J 0
(2310 2710);
DISPLAY 0.617021 (2310 2710);
PAINT ORANGE (2310 2710);
FORCEPROP 2 LASTPIN (2300 2650) $PN 178
J 0
(2310 2660);
DISPLAY 0.617021 (2310 2660);
PAINT ORANGE (2310 2660);
FORCEPROP 2 LASTPIN (2300 2600) $PN 180
J 0
(2310 2610);
DISPLAY 0.617021 (2310 2610);
PAINT ORANGE (2310 2610);
FORCEPROP 2 LASTPIN (2300 2550) $PN 182
J 0
(2310 2560);
DISPLAY 0.617021 (2310 2560);
PAINT ORANGE (2310 2560);
FORCEPROP 2 LASTPIN (2300 2500) $PN 184
J 0
(2310 2510);
DISPLAY 0.617021 (2310 2510);
PAINT ORANGE (2310 2510);
FORCEPROP 2 LASTPIN (2300 2450) $PN 187
J 0
(2310 2460);
DISPLAY 0.617021 (2310 2460);
PAINT ORANGE (2310 2460);
FORCEPROP 2 LASTPIN (2300 2400) $PN 189
J 0
(2310 2410);
DISPLAY 0.617021 (2310 2410);
PAINT ORANGE (2310 2410);
FORCEPROP 2 LASTPIN (2300 2350) $PN 191
J 0
(2310 2360);
DISPLAY 0.617021 (2310 2360);
PAINT ORANGE (2310 2360);
FORCEPROP 2 LASTPIN (2300 2300) $PN 193
J 0
(2310 2310);
DISPLAY 0.617021 (2310 2310);
PAINT ORANGE (2310 2310);
FORCEPROP 2 LASTPIN (2300 2250) $PN 195
J 0
(2310 2260);
DISPLAY 0.617021 (2310 2260);
PAINT ORANGE (2310 2260);
FORCEPROP 2 LASTPIN (2300 2200) $PN 198
J 0
(2310 2210);
DISPLAY 0.617021 (2310 2210);
PAINT ORANGE (2310 2210);
FORCEPROP 2 LASTPIN (2300 2150) $PN 200
J 0
(2310 2160);
DISPLAY 0.617021 (2310 2160);
PAINT ORANGE (2310 2160);
FORCEPROP 2 LASTPIN (2300 2100) $PN 202
J 0
(2310 2110);
DISPLAY 0.617021 (2310 2110);
PAINT ORANGE (2310 2110);
FORCEPROP 2 LASTPIN (2300 2050) $PN 239
J 0
(2310 2060);
DISPLAY 0.617021 (2310 2060);
PAINT ORANGE (2310 2060);
FORCEPROP 2 LASTPIN (2300 2000) $PN 241
J 0
(2310 2010);
DISPLAY 0.617021 (2310 2010);
PAINT ORANGE (2310 2010);
FORCEPROP 2 LASTPIN (2300 1950) $PN 243
J 0
(2310 1960);
DISPLAY 0.617021 (2310 1960);
PAINT ORANGE (2310 1960);
FORCEPROP 2 LASTPIN (2300 1900) $PN 246
J 0
(2310 1910);
DISPLAY 0.617021 (2310 1910);
PAINT ORANGE (2310 1910);
FORCEPROP 2 LASTPIN (2300 1850) $PN 248
J 0
(2310 1860);
DISPLAY 0.617021 (2310 1860);
PAINT ORANGE (2310 1860);
FORCEPROP 2 LASTPIN (2300 1800) $PN 250
J 0
(2310 1810);
DISPLAY 0.617021 (2310 1810);
PAINT ORANGE (2310 1810);
FORCEPROP 2 LASTPIN (2300 1750) $PN 252
J 0
(2310 1760);
DISPLAY 0.617021 (2310 1760);
PAINT ORANGE (2310 1760);
FORCEPROP 2 LASTPIN (2300 1700) $PN 254
J 0
(2310 1710);
DISPLAY 0.617021 (2310 1710);
PAINT ORANGE (2310 1710);
FORCEPROP 2 LASTPIN (2300 1650) $PN 257
J 0
(2310 1660);
DISPLAY 0.617021 (2310 1660);
PAINT ORANGE (2310 1660);
FORCEPROP 2 LASTPIN (2300 1600) $PN 259
J 0
(2310 1610);
DISPLAY 0.617021 (2310 1610);
PAINT ORANGE (2310 1610);
FORCEPROP 2 LASTPIN (2300 1550) $PN 261
J 0
(2310 1560);
DISPLAY 0.617021 (2310 1560);
PAINT ORANGE (2310 1560);
FORCEPROP 2 LASTPIN (2300 1500) $PN 263
J 0
(2310 1510);
DISPLAY 0.617021 (2310 1510);
PAINT ORANGE (2310 1510);
FORCEPROP 2 LASTPIN (2300 1450) $PN 265
J 0
(2310 1460);
DISPLAY 0.617021 (2310 1460);
PAINT ORANGE (2310 1460);
FORCEPROP 2 LASTPIN (2300 1400) $PN 268
J 0
(2310 1410);
DISPLAY 0.617021 (2310 1410);
PAINT ORANGE (2310 1410);
FORCEPROP 2 LASTPIN (2300 1350) $PN 270
J 0
(2310 1360);
DISPLAY 0.617021 (2310 1360);
PAINT ORANGE (2310 1360);
FORCEPROP 2 LASTPIN (2300 1300) $PN 272
J 0
(2310 1310);
DISPLAY 0.617021 (2310 1310);
PAINT ORANGE (2310 1310);
FORCEPROP 2 LASTPIN (2300 1250) $PN 274
J 0
(2310 1260);
DISPLAY 0.617021 (2310 1260);
PAINT ORANGE (2310 1260);
FORCEPROP 2 LASTPIN (2300 1200) $PN 276
J 0
(2310 1210);
DISPLAY 0.617021 (2310 1210);
PAINT ORANGE (2310 1210);
FORCEPROP 2 LASTPIN (2300 1150) $PN 279
J 0
(2310 1160);
DISPLAY 0.617021 (2310 1160);
PAINT ORANGE (2310 1160);
FORCEPROP 2 LASTPIN (2300 1100) $PN 281
J 0
(2310 1110);
DISPLAY 0.617021 (2310 1110);
PAINT ORANGE (2310 1110);
FORCEPROP 2 LASTPIN (2300 1050) $PN 283
J 0
(2310 1060);
DISPLAY 0.617021 (2310 1060);
PAINT ORANGE (2310 1060);
FORCEPROP 1 LAST PACK_TYPE PIP
J 0
(1350 3650);
PAINT SKYBLUE (1350 3650);
DISPLAY INVISIBLE (1350 3650);
FORCEPROP 2 LAST BOM_COST MEM
J 0
(1800 2200);
PAINT ORANGE (1800 2200);
DISPLAY INVISIBLE (1800 2200);
FORCEPROP 2 LAST CDS_LIB mstr_sconn
J 0
(1800 2200);
PAINT ORANGE (1800 2200);
DISPLAY INVISIBLE (1800 2200);
FORCEPROP 2 LAST SEC_TYPE PIP
J 0
(1350 3650);
DISPLAY 1.021277 (1350 3650);
PAINT ORANGE (1350 3650);
DISPLAY INVISIBLE (1350 3650);
FORCEPROP 2 LAST SEC 3
J 0
(1350 3650);
DISPLAY 0.680851 (1350 3650);
PAINT MONO (1350 3650);
DISPLAY INVISIBLE (1350 3650);
FORCEPROP 2 LAST CDS_LOCATION J1G1
J 0
(1350 3600);
DISPLAY 0.617021 (1350 3600);
PAINT AQUA (1350 3600);
DISPLAY INVISIBLE (1350 3600);
FORCEPROP 1 LAST PATH I43
J 0
(1800 3550);
PAINT GREEN (1800 3550);
DISPLAY INVISIBLE (1800 3550);
FORCEPROP 2 LAST ROOM DDR4_CH_G
J 0
(1800 2200);
PAINT ORANGE (1800 2200);
DISPLAY INVISIBLE (1800 2200);
FORCEADD GND..1
R 2
(1100 900);
FORCEPROP 3 LASTPIN (1100 950) SIG_NAME GND\g
J 0
(1110 960);
DISPLAY 0.659574 (1110 960);
PAINT MONO (1110 960);
DISPLAY INVISIBLE (1110 960);
FORCEPROP 1 LAST VOLTAGE 0
J 0
(1100 900);
PAINT SKYBLUE (1100 900);
DISPLAY INVISIBLE (1100 900);
FORCEPROP 1 LAST SIZE 1B
J 2
(1025 850);
DISPLAY 1.170213 (1025 850);
PAINT GREEN (1025 850);
DISPLAY INVISIBLE (1025 850);
FORCEPROP 2 LAST CDS_LIB mstr_symbols
J 0
(1100 900);
DISPLAY 0.787234 (1100 900);
PAINT MONO (1100 900);
DISPLAY INVISIBLE (1100 900);
FORCEPROP 2 LAST BOM_COST MEM
J 0
(1100 905);
PAINT ORANGE (1100 905);
DISPLAY INVISIBLE (1100 905);
FORCEPROP 1 LAST BODY_TYPE PLUMBING
J 2
(1145 857);
DISPLAY 0.340426 (1145 857);
PAINT GREEN (1145 857);
DISPLAY INVISIBLE (1145 857);
FORCEPROP 1 LAST PATH I44
J 2
(1025 900);
DISPLAY 0.936170 (1025 900);
PAINT GREEN (1025 900);
DISPLAY INVISIBLE (1025 900);
FORCEPROP 2 LAST ROOM DDR4_CH_G
J 0
(1100 905);
PAINT ORANGE (1100 905);
DISPLAY INVISIBLE (1100 905);
FORCEPROP 1 LAST HDL_POWER GND
J 2
(1100 1050);
DISPLAY 0.553191 (1100 1050);
PAINT GREEN (1100 1050);
DISPLAY INVISIBLE (1100 1050);
FORCEADD OFFPAGE..3
(-1075 4475);
FORCEPROP 2 LAST $XR0 57 
J 0
(-861 4475);
DISPLAY 0.638298 (-861 4475);
PAINT MONO (-861 4475);
FORCEPROP 2 LAST $XR1 78 
J 0
(-771 4475);
DISPLAY 0.638298 (-771 4475);
PAINT MONO (-771 4475);
FORCEPROP 2 LAST CDS_LIB mstr_standard
J 0
(-1075 4475);
DISPLAY 0.787234 (-1075 4475);
PAINT MONO (-1075 4475);
DISPLAY INVISIBLE (-1075 4475);
FORCEPROP 1 LAST OFFPAGE TRUE
J 0
(-750 4350);
DISPLAY 0.936170 (-750 4350);
PAINT GREEN (-750 4350);
DISPLAY INVISIBLE (-750 4350);
FORCEPROP 1 LAST COMMENT_BODY TRUE
J 0
(-1125 4375);
DISPLAY 0.936170 (-1125 4375);
PAINT GREEN (-1125 4375);
DISPLAY INVISIBLE (-1125 4375);
FORCEPROP 2 LAST PATH I45
J 0
(-875 4550);
DISPLAY 0.787234 (-875 4550);
PAINT MONO (-875 4550);
DISPLAY INVISIBLE (-875 4550);
FORCEADD TAP..6
R 2
(-1625 4375);
FORCEPROP 3 LASTPIN (-1675 4375) SIG_NAME M_G_DQ<63>
J 0
(-1665 4385);
DISPLAY 0.659574 (-1665 4385);
PAINT MONO (-1665 4385);
DISPLAY INVISIBLE (-1665 4385);
FORCEPROP 1 LASTPIN (-1675 4375) BN 63
J 2
(-1625 4385);
DISPLAY 0.617021 (-1625 4385);
PAINT PINK (-1625 4385);
FORCEPROP 2 LAST CDS_LIB mstr_standard
J 2
(-1625 4375);
DISPLAY 0.787234 (-1625 4375);
PAINT MONO (-1625 4375);
DISPLAY INVISIBLE (-1625 4375);
FORCEPROP 1 LAST BODY_TYPE PLUMBING
J 2
(-1625 4325);
DISPLAY 1.234043 (-1625 4325);
PAINT GREEN (-1625 4325);
DISPLAY INVISIBLE (-1625 4325);
FORCEPROP 1 LAST HDL_TAP TRUE
J 2
(-1950 4250);
DISPLAY 1.234043 (-1950 4250);
PAINT GREEN (-1950 4250);
DISPLAY INVISIBLE (-1950 4250);
FORCEPROP 1 LAST PATH I46
J 2
(-1625 4375);
DISPLAY 0.936170 (-1625 4375);
PAINT GREEN (-1625 4375);
DISPLAY INVISIBLE (-1625 4375);
FORCEADD TAP..6
R 2
(-1625 4425);
FORCEPROP 3 LASTPIN (-1675 4425) SIG_NAME M_G_DQ<62>
J 0
(-1665 4435);
DISPLAY 0.659574 (-1665 4435);
PAINT MONO (-1665 4435);
DISPLAY INVISIBLE (-1665 4435);
FORCEPROP 1 LASTPIN (-1675 4425) BN 62
J 2
(-1625 4435);
DISPLAY 0.617021 (-1625 4435);
PAINT PINK (-1625 4435);
FORCEPROP 2 LAST CDS_LIB mstr_standard
J 2
(-1625 4425);
DISPLAY 0.787234 (-1625 4425);
PAINT MONO (-1625 4425);
DISPLAY INVISIBLE (-1625 4425);
FORCEPROP 1 LAST BODY_TYPE PLUMBING
J 2
(-1625 4375);
DISPLAY 1.234043 (-1625 4375);
PAINT GREEN (-1625 4375);
DISPLAY INVISIBLE (-1625 4375);
FORCEPROP 1 LAST HDL_TAP TRUE
J 2
(-1950 4300);
DISPLAY 1.234043 (-1950 4300);
PAINT GREEN (-1950 4300);
DISPLAY INVISIBLE (-1950 4300);
FORCEPROP 1 LAST PATH I47
J 2
(-1625 4425);
DISPLAY 0.936170 (-1625 4425);
PAINT GREEN (-1625 4425);
DISPLAY INVISIBLE (-1625 4425);
FORCEADD TAP..6
R 2
(-1625 4275);
FORCEPROP 3 LASTPIN (-1675 4275) SIG_NAME M_G_DQ<61>
J 0
(-1665 4285);
DISPLAY 0.659574 (-1665 4285);
PAINT MONO (-1665 4285);
DISPLAY INVISIBLE (-1665 4285);
FORCEPROP 1 LASTPIN (-1675 4275) BN 61
J 2
(-1625 4285);
DISPLAY 0.617021 (-1625 4285);
PAINT PINK (-1625 4285);
FORCEPROP 2 LAST CDS_LIB mstr_standard
J 2
(-1625 4275);
DISPLAY 0.787234 (-1625 4275);
PAINT MONO (-1625 4275);
DISPLAY INVISIBLE (-1625 4275);
FORCEPROP 1 LAST BODY_TYPE PLUMBING
J 2
(-1625 4225);
DISPLAY 1.234043 (-1625 4225);
PAINT GREEN (-1625 4225);
DISPLAY INVISIBLE (-1625 4225);
FORCEPROP 1 LAST HDL_TAP TRUE
J 2
(-1950 4150);
DISPLAY 1.234043 (-1950 4150);
PAINT GREEN (-1950 4150);
DISPLAY INVISIBLE (-1950 4150);
FORCEPROP 1 LAST PATH I48
J 2
(-1625 4275);
DISPLAY 0.936170 (-1625 4275);
PAINT GREEN (-1625 4275);
DISPLAY INVISIBLE (-1625 4275);
FORCEADD TAP..6
R 2
(-1625 4325);
FORCEPROP 3 LASTPIN (-1675 4325) SIG_NAME M_G_DQ<60>
J 0
(-1665 4335);
DISPLAY 0.659574 (-1665 4335);
PAINT MONO (-1665 4335);
DISPLAY INVISIBLE (-1665 4335);
FORCEPROP 1 LASTPIN (-1675 4325) BN 60
J 2
(-1625 4335);
DISPLAY 0.617021 (-1625 4335);
PAINT PINK (-1625 4335);
FORCEPROP 2 LAST CDS_LIB mstr_standard
J 2
(-1625 4325);
DISPLAY 0.787234 (-1625 4325);
PAINT MONO (-1625 4325);
DISPLAY INVISIBLE (-1625 4325);
FORCEPROP 1 LAST BODY_TYPE PLUMBING
J 2
(-1625 4275);
DISPLAY 1.234043 (-1625 4275);
PAINT GREEN (-1625 4275);
DISPLAY INVISIBLE (-1625 4275);
FORCEPROP 1 LAST HDL_TAP TRUE
J 2
(-1950 4200);
DISPLAY 1.234043 (-1950 4200);
PAINT GREEN (-1950 4200);
DISPLAY INVISIBLE (-1950 4200);
FORCEPROP 1 LAST PATH I49
J 2
(-1625 4325);
DISPLAY 0.936170 (-1625 4325);
PAINT GREEN (-1625 4325);
DISPLAY INVISIBLE (-1625 4325);
FORCEADD TAP..6
R 2
(900 4800);
FORCEPROP 3 LASTPIN (850 4800) SIG_NAME M_G_DQS_DN<15>
J 0
(860 4810);
DISPLAY 0.659574 (860 4810);
PAINT MONO (860 4810);
DISPLAY INVISIBLE (860 4810);
FORCEPROP 1 LASTPIN (850 4800) BN 15
J 2
(900 4810);
DISPLAY 0.617021 (900 4810);
PAINT PINK (900 4810);
FORCEPROP 2 LAST CDS_LIB mstr_standard
J 0
(900 4800);
DISPLAY 0.787234 (900 4800);
PAINT MONO (900 4800);
DISPLAY INVISIBLE (900 4800);
FORCEPROP 1 LAST BODY_TYPE PLUMBING
J 2
(900 4750);
DISPLAY 1.234043 (900 4750);
PAINT GREEN (900 4750);
DISPLAY INVISIBLE (900 4750);
FORCEPROP 1 LAST HDL_TAP TRUE
J 2
(575 4675);
DISPLAY 1.234043 (575 4675);
PAINT GREEN (575 4675);
DISPLAY INVISIBLE (575 4675);
FORCEPROP 1 LAST PATH I5
J 2
(900 4800);
DISPLAY 0.936170 (900 4800);
PAINT GREEN (900 4800);
DISPLAY INVISIBLE (900 4800);
FORCEADD TAP..6
R 2
(-1625 4225);
FORCEPROP 3 LASTPIN (-1675 4225) SIG_NAME M_G_DQ<58>
J 0
(-1665 4235);
DISPLAY 0.659574 (-1665 4235);
PAINT MONO (-1665 4235);
DISPLAY INVISIBLE (-1665 4235);
FORCEPROP 1 LASTPIN (-1675 4225) BN 58
J 2
(-1625 4235);
DISPLAY 0.617021 (-1625 4235);
PAINT PINK (-1625 4235);
FORCEPROP 2 LAST CDS_LIB mstr_standard
J 2
(-1625 4225);
DISPLAY 0.787234 (-1625 4225);
PAINT MONO (-1625 4225);
DISPLAY INVISIBLE (-1625 4225);
FORCEPROP 1 LAST BODY_TYPE PLUMBING
J 2
(-1625 4175);
DISPLAY 1.234043 (-1625 4175);
PAINT GREEN (-1625 4175);
DISPLAY INVISIBLE (-1625 4175);
FORCEPROP 1 LAST HDL_TAP TRUE
J 2
(-1950 4100);
DISPLAY 1.234043 (-1950 4100);
PAINT GREEN (-1950 4100);
DISPLAY INVISIBLE (-1950 4100);
FORCEPROP 1 LAST PATH I50
J 2
(-1625 4225);
DISPLAY 0.936170 (-1625 4225);
PAINT GREEN (-1625 4225);
DISPLAY INVISIBLE (-1625 4225);
FORCEADD TAP..6
R 2
(-1625 4175);
FORCEPROP 3 LASTPIN (-1675 4175) SIG_NAME M_G_DQ<59>
J 0
(-1665 4185);
DISPLAY 0.659574 (-1665 4185);
PAINT MONO (-1665 4185);
DISPLAY INVISIBLE (-1665 4185);
FORCEPROP 1 LASTPIN (-1675 4175) BN 59
J 2
(-1625 4185);
DISPLAY 0.617021 (-1625 4185);
PAINT PINK (-1625 4185);
FORCEPROP 2 LAST CDS_LIB mstr_standard
J 2
(-1625 4175);
DISPLAY 0.787234 (-1625 4175);
PAINT MONO (-1625 4175);
DISPLAY INVISIBLE (-1625 4175);
FORCEPROP 1 LAST BODY_TYPE PLUMBING
J 2
(-1625 4125);
DISPLAY 1.234043 (-1625 4125);
PAINT GREEN (-1625 4125);
DISPLAY INVISIBLE (-1625 4125);
FORCEPROP 1 LAST HDL_TAP TRUE
J 2
(-1950 4050);
DISPLAY 1.234043 (-1950 4050);
PAINT GREEN (-1950 4050);
DISPLAY INVISIBLE (-1950 4050);
FORCEPROP 1 LAST PATH I51
J 2
(-1625 4175);
DISPLAY 0.936170 (-1625 4175);
PAINT GREEN (-1625 4175);
DISPLAY INVISIBLE (-1625 4175);
FORCEADD TAP..6
R 2
(-1625 4125);
FORCEPROP 3 LASTPIN (-1675 4125) SIG_NAME M_G_DQ<56>
J 0
(-1665 4135);
DISPLAY 0.659574 (-1665 4135);
PAINT MONO (-1665 4135);
DISPLAY INVISIBLE (-1665 4135);
FORCEPROP 1 LASTPIN (-1675 4125) BN 56
J 2
(-1625 4135);
DISPLAY 0.617021 (-1625 4135);
PAINT PINK (-1625 4135);
FORCEPROP 2 LAST CDS_LIB mstr_standard
J 2
(-1625 4125);
DISPLAY 0.787234 (-1625 4125);
PAINT MONO (-1625 4125);
DISPLAY INVISIBLE (-1625 4125);
FORCEPROP 1 LAST BODY_TYPE PLUMBING
J 2
(-1625 4075);
DISPLAY 1.234043 (-1625 4075);
PAINT GREEN (-1625 4075);
DISPLAY INVISIBLE (-1625 4075);
FORCEPROP 1 LAST HDL_TAP TRUE
J 2
(-1950 4000);
DISPLAY 1.234043 (-1950 4000);
PAINT GREEN (-1950 4000);
DISPLAY INVISIBLE (-1950 4000);
FORCEPROP 1 LAST PATH I52
J 2
(-1625 4125);
DISPLAY 0.936170 (-1625 4125);
PAINT GREEN (-1625 4125);
DISPLAY INVISIBLE (-1625 4125);
FORCEADD TAP..6
R 2
(-1625 4075);
FORCEPROP 3 LASTPIN (-1675 4075) SIG_NAME M_G_DQ<57>
J 0
(-1665 4085);
DISPLAY 0.659574 (-1665 4085);
PAINT MONO (-1665 4085);
DISPLAY INVISIBLE (-1665 4085);
FORCEPROP 1 LASTPIN (-1675 4075) BN 57
J 2
(-1625 4085);
DISPLAY 0.617021 (-1625 4085);
PAINT PINK (-1625 4085);
FORCEPROP 2 LAST CDS_LIB mstr_standard
J 2
(-1625 4075);
DISPLAY 0.787234 (-1625 4075);
PAINT MONO (-1625 4075);
DISPLAY INVISIBLE (-1625 4075);
FORCEPROP 1 LAST BODY_TYPE PLUMBING
J 2
(-1625 4025);
DISPLAY 1.234043 (-1625 4025);
PAINT GREEN (-1625 4025);
DISPLAY INVISIBLE (-1625 4025);
FORCEPROP 1 LAST HDL_TAP TRUE
J 2
(-1950 3950);
DISPLAY 1.234043 (-1950 3950);
PAINT GREEN (-1950 3950);
DISPLAY INVISIBLE (-1950 3950);
FORCEPROP 1 LAST PATH I53
J 2
(-1625 4075);
DISPLAY 0.936170 (-1625 4075);
PAINT GREEN (-1625 4075);
DISPLAY INVISIBLE (-1625 4075);
FORCEADD TAP..6
R 2
(-1625 4025);
FORCEPROP 3 LASTPIN (-1675 4025) SIG_NAME M_G_DQ<54>
J 0
(-1665 4035);
DISPLAY 0.659574 (-1665 4035);
PAINT MONO (-1665 4035);
DISPLAY INVISIBLE (-1665 4035);
FORCEPROP 1 LASTPIN (-1675 4025) BN 54
J 2
(-1625 4035);
DISPLAY 0.617021 (-1625 4035);
PAINT PINK (-1625 4035);
FORCEPROP 2 LAST CDS_LIB mstr_standard
J 2
(-1625 4025);
DISPLAY 0.787234 (-1625 4025);
PAINT MONO (-1625 4025);
DISPLAY INVISIBLE (-1625 4025);
FORCEPROP 1 LAST BODY_TYPE PLUMBING
J 2
(-1625 3975);
DISPLAY 1.234043 (-1625 3975);
PAINT GREEN (-1625 3975);
DISPLAY INVISIBLE (-1625 3975);
FORCEPROP 1 LAST HDL_TAP TRUE
J 2
(-1950 3900);
DISPLAY 1.234043 (-1950 3900);
PAINT GREEN (-1950 3900);
DISPLAY INVISIBLE (-1950 3900);
FORCEPROP 1 LAST PATH I54
J 2
(-1625 4025);
DISPLAY 0.936170 (-1625 4025);
PAINT GREEN (-1625 4025);
DISPLAY INVISIBLE (-1625 4025);
FORCEADD TAP..6
R 2
(-1625 3875);
FORCEPROP 3 LASTPIN (-1675 3875) SIG_NAME M_G_DQ<53>
J 0
(-1665 3885);
DISPLAY 0.659574 (-1665 3885);
PAINT MONO (-1665 3885);
DISPLAY INVISIBLE (-1665 3885);
FORCEPROP 1 LASTPIN (-1675 3875) BN 53
J 2
(-1625 3885);
DISPLAY 0.617021 (-1625 3885);
PAINT PINK (-1625 3885);
FORCEPROP 2 LAST CDS_LIB mstr_standard
J 2
(-1625 3875);
DISPLAY 0.787234 (-1625 3875);
PAINT MONO (-1625 3875);
DISPLAY INVISIBLE (-1625 3875);
FORCEPROP 1 LAST BODY_TYPE PLUMBING
J 2
(-1625 3825);
DISPLAY 1.234043 (-1625 3825);
PAINT GREEN (-1625 3825);
DISPLAY INVISIBLE (-1625 3825);
FORCEPROP 1 LAST HDL_TAP TRUE
J 2
(-1950 3750);
DISPLAY 1.234043 (-1950 3750);
PAINT GREEN (-1950 3750);
DISPLAY INVISIBLE (-1950 3750);
FORCEPROP 1 LAST PATH I55
J 2
(-1625 3875);
DISPLAY 0.936170 (-1625 3875);
PAINT GREEN (-1625 3875);
DISPLAY INVISIBLE (-1625 3875);
FORCEADD TAP..6
R 2
(-1625 3975);
FORCEPROP 3 LASTPIN (-1675 3975) SIG_NAME M_G_DQ<55>
J 0
(-1665 3985);
DISPLAY 0.659574 (-1665 3985);
PAINT MONO (-1665 3985);
DISPLAY INVISIBLE (-1665 3985);
FORCEPROP 1 LASTPIN (-1675 3975) BN 55
J 2
(-1625 3985);
DISPLAY 0.617021 (-1625 3985);
PAINT PINK (-1625 3985);
FORCEPROP 2 LAST CDS_LIB mstr_standard
J 2
(-1625 3975);
DISPLAY 0.787234 (-1625 3975);
PAINT MONO (-1625 3975);
DISPLAY INVISIBLE (-1625 3975);
FORCEPROP 1 LAST BODY_TYPE PLUMBING
J 2
(-1625 3925);
DISPLAY 1.234043 (-1625 3925);
PAINT GREEN (-1625 3925);
DISPLAY INVISIBLE (-1625 3925);
FORCEPROP 1 LAST HDL_TAP TRUE
J 2
(-1950 3850);
DISPLAY 1.234043 (-1950 3850);
PAINT GREEN (-1950 3850);
DISPLAY INVISIBLE (-1950 3850);
FORCEPROP 1 LAST PATH I56
J 2
(-1625 3975);
DISPLAY 0.936170 (-1625 3975);
PAINT GREEN (-1625 3975);
DISPLAY INVISIBLE (-1625 3975);
FORCEADD TAP..6
R 2
(-1625 3925);
FORCEPROP 3 LASTPIN (-1675 3925) SIG_NAME M_G_DQ<52>
J 0
(-1665 3935);
DISPLAY 0.659574 (-1665 3935);
PAINT MONO (-1665 3935);
DISPLAY INVISIBLE (-1665 3935);
FORCEPROP 1 LASTPIN (-1675 3925) BN 52
J 2
(-1625 3935);
DISPLAY 0.617021 (-1625 3935);
PAINT PINK (-1625 3935);
FORCEPROP 2 LAST CDS_LIB mstr_standard
J 2
(-1625 3925);
DISPLAY 0.787234 (-1625 3925);
PAINT MONO (-1625 3925);
DISPLAY INVISIBLE (-1625 3925);
FORCEPROP 1 LAST BODY_TYPE PLUMBING
J 2
(-1625 3875);
DISPLAY 1.234043 (-1625 3875);
PAINT GREEN (-1625 3875);
DISPLAY INVISIBLE (-1625 3875);
FORCEPROP 1 LAST HDL_TAP TRUE
J 2
(-1950 3800);
DISPLAY 1.234043 (-1950 3800);
PAINT GREEN (-1950 3800);
DISPLAY INVISIBLE (-1950 3800);
FORCEPROP 1 LAST PATH I57
J 2
(-1625 3925);
DISPLAY 0.936170 (-1625 3925);
PAINT GREEN (-1625 3925);
DISPLAY INVISIBLE (-1625 3925);
FORCEADD TAP..6
R 2
(-1625 3825);
FORCEPROP 3 LASTPIN (-1675 3825) SIG_NAME M_G_DQ<50>
J 0
(-1665 3835);
DISPLAY 0.659574 (-1665 3835);
PAINT MONO (-1665 3835);
DISPLAY INVISIBLE (-1665 3835);
FORCEPROP 1 LASTPIN (-1675 3825) BN 50
J 2
(-1625 3835);
DISPLAY 0.617021 (-1625 3835);
PAINT PINK (-1625 3835);
FORCEPROP 2 LAST CDS_LIB mstr_standard
J 2
(-1625 3825);
DISPLAY 0.787234 (-1625 3825);
PAINT MONO (-1625 3825);
DISPLAY INVISIBLE (-1625 3825);
FORCEPROP 1 LAST BODY_TYPE PLUMBING
J 2
(-1625 3775);
DISPLAY 1.234043 (-1625 3775);
PAINT GREEN (-1625 3775);
DISPLAY INVISIBLE (-1625 3775);
FORCEPROP 1 LAST HDL_TAP TRUE
J 2
(-1950 3700);
DISPLAY 1.234043 (-1950 3700);
PAINT GREEN (-1950 3700);
DISPLAY INVISIBLE (-1950 3700);
FORCEPROP 1 LAST PATH I58
J 2
(-1625 3825);
DISPLAY 0.936170 (-1625 3825);
PAINT GREEN (-1625 3825);
DISPLAY INVISIBLE (-1625 3825);
FORCEADD TAP..6
R 2
(-1625 3775);
FORCEPROP 3 LASTPIN (-1675 3775) SIG_NAME M_G_DQ<51>
J 0
(-1665 3785);
DISPLAY 0.659574 (-1665 3785);
PAINT MONO (-1665 3785);
DISPLAY INVISIBLE (-1665 3785);
FORCEPROP 1 LASTPIN (-1675 3775) BN 51
J 2
(-1625 3785);
DISPLAY 0.617021 (-1625 3785);
PAINT PINK (-1625 3785);
FORCEPROP 2 LAST CDS_LIB mstr_standard
J 2
(-1625 3775);
DISPLAY 0.787234 (-1625 3775);
PAINT MONO (-1625 3775);
DISPLAY INVISIBLE (-1625 3775);
FORCEPROP 1 LAST BODY_TYPE PLUMBING
J 2
(-1625 3725);
DISPLAY 1.234043 (-1625 3725);
PAINT GREEN (-1625 3725);
DISPLAY INVISIBLE (-1625 3725);
FORCEPROP 1 LAST HDL_TAP TRUE
J 2
(-1950 3650);
DISPLAY 1.234043 (-1950 3650);
PAINT GREEN (-1950 3650);
DISPLAY INVISIBLE (-1950 3650);
FORCEPROP 1 LAST PATH I59
J 2
(-1625 3775);
DISPLAY 0.936170 (-1625 3775);
PAINT GREEN (-1625 3775);
DISPLAY INVISIBLE (-1625 3775);
FORCEADD TAP..6
R 2
(900 4900);
FORCEPROP 3 LASTPIN (850 4900) SIG_NAME M_G_DQS_DN<16>
J 0
(860 4910);
DISPLAY 0.659574 (860 4910);
PAINT MONO (860 4910);
DISPLAY INVISIBLE (860 4910);
FORCEPROP 1 LASTPIN (850 4900) BN 16
J 2
(900 4910);
DISPLAY 0.617021 (900 4910);
PAINT PINK (900 4910);
FORCEPROP 2 LAST CDS_LIB mstr_standard
J 0
(900 4900);
DISPLAY 0.787234 (900 4900);
PAINT MONO (900 4900);
DISPLAY INVISIBLE (900 4900);
FORCEPROP 1 LAST BODY_TYPE PLUMBING
J 2
(900 4850);
DISPLAY 1.234043 (900 4850);
PAINT GREEN (900 4850);
DISPLAY INVISIBLE (900 4850);
FORCEPROP 1 LAST HDL_TAP TRUE
J 2
(575 4775);
DISPLAY 1.234043 (575 4775);
PAINT GREEN (575 4775);
DISPLAY INVISIBLE (575 4775);
FORCEPROP 1 LAST PATH I6
J 2
(900 4900);
DISPLAY 0.936170 (900 4900);
PAINT GREEN (900 4900);
DISPLAY INVISIBLE (900 4900);
FORCEADD TAP..6
R 2
(-1625 3725);
FORCEPROP 3 LASTPIN (-1675 3725) SIG_NAME M_G_DQ<48>
J 0
(-1665 3735);
DISPLAY 0.659574 (-1665 3735);
PAINT MONO (-1665 3735);
DISPLAY INVISIBLE (-1665 3735);
FORCEPROP 1 LASTPIN (-1675 3725) BN 48
J 2
(-1625 3735);
DISPLAY 0.617021 (-1625 3735);
PAINT PINK (-1625 3735);
FORCEPROP 2 LAST CDS_LIB mstr_standard
J 2
(-1625 3725);
DISPLAY 0.787234 (-1625 3725);
PAINT MONO (-1625 3725);
DISPLAY INVISIBLE (-1625 3725);
FORCEPROP 1 LAST BODY_TYPE PLUMBING
J 2
(-1625 3675);
DISPLAY 1.234043 (-1625 3675);
PAINT GREEN (-1625 3675);
DISPLAY INVISIBLE (-1625 3675);
FORCEPROP 1 LAST HDL_TAP TRUE
J 2
(-1950 3600);
DISPLAY 1.234043 (-1950 3600);
PAINT GREEN (-1950 3600);
DISPLAY INVISIBLE (-1950 3600);
FORCEPROP 1 LAST PATH I60
J 2
(-1625 3725);
DISPLAY 0.936170 (-1625 3725);
PAINT GREEN (-1625 3725);
DISPLAY INVISIBLE (-1625 3725);
FORCEADD TAP..6
R 2
(-1625 3575);
FORCEPROP 3 LASTPIN (-1675 3575) SIG_NAME M_G_DQ<47>
J 0
(-1665 3585);
DISPLAY 0.659574 (-1665 3585);
PAINT MONO (-1665 3585);
DISPLAY INVISIBLE (-1665 3585);
FORCEPROP 1 LASTPIN (-1675 3575) BN 47
J 2
(-1625 3585);
DISPLAY 0.617021 (-1625 3585);
PAINT PINK (-1625 3585);
FORCEPROP 2 LAST CDS_LIB mstr_standard
J 2
(-1625 3575);
DISPLAY 0.787234 (-1625 3575);
PAINT MONO (-1625 3575);
DISPLAY INVISIBLE (-1625 3575);
FORCEPROP 1 LAST BODY_TYPE PLUMBING
J 2
(-1625 3525);
DISPLAY 1.234043 (-1625 3525);
PAINT GREEN (-1625 3525);
DISPLAY INVISIBLE (-1625 3525);
FORCEPROP 1 LAST HDL_TAP TRUE
J 2
(-1950 3450);
DISPLAY 1.234043 (-1950 3450);
PAINT GREEN (-1950 3450);
DISPLAY INVISIBLE (-1950 3450);
FORCEPROP 1 LAST PATH I61
J 2
(-1625 3575);
DISPLAY 0.936170 (-1625 3575);
PAINT GREEN (-1625 3575);
DISPLAY INVISIBLE (-1625 3575);
FORCEADD TAP..6
R 2
(-1625 3675);
FORCEPROP 3 LASTPIN (-1675 3675) SIG_NAME M_G_DQ<49>
J 0
(-1665 3685);
DISPLAY 0.659574 (-1665 3685);
PAINT MONO (-1665 3685);
DISPLAY INVISIBLE (-1665 3685);
FORCEPROP 1 LASTPIN (-1675 3675) BN 49
J 2
(-1625 3685);
DISPLAY 0.617021 (-1625 3685);
PAINT PINK (-1625 3685);
FORCEPROP 2 LAST CDS_LIB mstr_standard
J 2
(-1625 3675);
DISPLAY 0.787234 (-1625 3675);
PAINT MONO (-1625 3675);
DISPLAY INVISIBLE (-1625 3675);
FORCEPROP 1 LAST BODY_TYPE PLUMBING
J 2
(-1625 3625);
DISPLAY 1.234043 (-1625 3625);
PAINT GREEN (-1625 3625);
DISPLAY INVISIBLE (-1625 3625);
FORCEPROP 1 LAST HDL_TAP TRUE
J 2
(-1950 3550);
DISPLAY 1.234043 (-1950 3550);
PAINT GREEN (-1950 3550);
DISPLAY INVISIBLE (-1950 3550);
FORCEPROP 1 LAST PATH I62
J 2
(-1625 3675);
DISPLAY 0.936170 (-1625 3675);
PAINT GREEN (-1625 3675);
DISPLAY INVISIBLE (-1625 3675);
FORCEADD TAP..6
R 2
(-1625 3625);
FORCEPROP 3 LASTPIN (-1675 3625) SIG_NAME M_G_DQ<46>
J 0
(-1665 3635);
DISPLAY 0.659574 (-1665 3635);
PAINT MONO (-1665 3635);
DISPLAY INVISIBLE (-1665 3635);
FORCEPROP 1 LASTPIN (-1675 3625) BN 46
J 2
(-1625 3635);
DISPLAY 0.617021 (-1625 3635);
PAINT PINK (-1625 3635);
FORCEPROP 2 LAST CDS_LIB mstr_standard
J 2
(-1625 3625);
DISPLAY 0.787234 (-1625 3625);
PAINT MONO (-1625 3625);
DISPLAY INVISIBLE (-1625 3625);
FORCEPROP 1 LAST BODY_TYPE PLUMBING
J 2
(-1625 3575);
DISPLAY 1.234043 (-1625 3575);
PAINT GREEN (-1625 3575);
DISPLAY INVISIBLE (-1625 3575);
FORCEPROP 1 LAST HDL_TAP TRUE
J 2
(-1950 3500);
DISPLAY 1.234043 (-1950 3500);
PAINT GREEN (-1950 3500);
DISPLAY INVISIBLE (-1950 3500);
FORCEPROP 1 LAST PATH I63
J 2
(-1625 3625);
DISPLAY 0.936170 (-1625 3625);
PAINT GREEN (-1625 3625);
DISPLAY INVISIBLE (-1625 3625);
FORCEADD TAP..6
R 2
(-1625 3525);
FORCEPROP 3 LASTPIN (-1675 3525) SIG_NAME M_G_DQ<44>
J 0
(-1665 3535);
DISPLAY 0.659574 (-1665 3535);
PAINT MONO (-1665 3535);
DISPLAY INVISIBLE (-1665 3535);
FORCEPROP 1 LASTPIN (-1675 3525) BN 44
J 2
(-1625 3535);
DISPLAY 0.617021 (-1625 3535);
PAINT PINK (-1625 3535);
FORCEPROP 2 LAST CDS_LIB mstr_standard
J 2
(-1625 3525);
DISPLAY 0.787234 (-1625 3525);
PAINT MONO (-1625 3525);
DISPLAY INVISIBLE (-1625 3525);
FORCEPROP 1 LAST BODY_TYPE PLUMBING
J 2
(-1625 3475);
DISPLAY 1.234043 (-1625 3475);
PAINT GREEN (-1625 3475);
DISPLAY INVISIBLE (-1625 3475);
FORCEPROP 1 LAST HDL_TAP TRUE
J 2
(-1950 3400);
DISPLAY 1.234043 (-1950 3400);
PAINT GREEN (-1950 3400);
DISPLAY INVISIBLE (-1950 3400);
FORCEPROP 1 LAST PATH I64
J 2
(-1625 3525);
DISPLAY 0.936170 (-1625 3525);
PAINT GREEN (-1625 3525);
DISPLAY INVISIBLE (-1625 3525);
FORCEADD TAP..6
R 2
(-1625 3475);
FORCEPROP 3 LASTPIN (-1675 3475) SIG_NAME M_G_DQ<45>
J 0
(-1665 3485);
DISPLAY 0.659574 (-1665 3485);
PAINT MONO (-1665 3485);
DISPLAY INVISIBLE (-1665 3485);
FORCEPROP 1 LASTPIN (-1675 3475) BN 45
J 2
(-1625 3485);
DISPLAY 0.617021 (-1625 3485);
PAINT PINK (-1625 3485);
FORCEPROP 2 LAST CDS_LIB mstr_standard
J 2
(-1625 3475);
DISPLAY 0.787234 (-1625 3475);
PAINT MONO (-1625 3475);
DISPLAY INVISIBLE (-1625 3475);
FORCEPROP 1 LAST BODY_TYPE PLUMBING
J 2
(-1625 3425);
DISPLAY 1.234043 (-1625 3425);
PAINT GREEN (-1625 3425);
DISPLAY INVISIBLE (-1625 3425);
FORCEPROP 1 LAST HDL_TAP TRUE
J 2
(-1950 3350);
DISPLAY 1.234043 (-1950 3350);
PAINT GREEN (-1950 3350);
DISPLAY INVISIBLE (-1950 3350);
FORCEPROP 1 LAST PATH I65
J 2
(-1625 3475);
DISPLAY 0.936170 (-1625 3475);
PAINT GREEN (-1625 3475);
DISPLAY INVISIBLE (-1625 3475);
FORCEADD SCONN288_H44441004..2
(0 4200);
FORCEPROP 1 LAST LOCATION J1G1
J 0
(-400 5300);
DISPLAY 0.617021 (-400 5300);
PAINT AQUA (-400 5300);
FORCEPROP 1 LAST PART_NUMBER H44441-004
J 0
(-400 3100);
DISPLAY 0.617021 (-400 3100);
PAINT BLUE (-400 3100);
FORCEPROP 1 LAST MATERIAL SCONN
J 0
(-400 5250);
DISPLAY 0.617021 (-400 5250);
PAINT SKYBLUE (-400 5250);
FORCEPROP 2 LASTPIN (450 5050) $PN 51
J 0
(460 5060);
DISPLAY 0.617021 (460 5060);
PAINT ORANGE (460 5060);
FORCEPROP 2 LASTPIN (450 5000) $PN 52
J 0
(460 5010);
DISPLAY 0.617021 (460 5010);
PAINT ORANGE (460 5010);
FORCEPROP 2 LASTPIN (450 4950) $PN 132
J 0
(460 4960);
DISPLAY 0.617021 (460 4960);
PAINT ORANGE (460 4960);
FORCEPROP 2 LASTPIN (450 4900) $PN 133
J 0
(460 4910);
DISPLAY 0.617021 (460 4910);
PAINT ORANGE (460 4910);
FORCEPROP 2 LASTPIN (450 4850) $PN 121
J 0
(460 4860);
DISPLAY 0.617021 (460 4860);
PAINT ORANGE (460 4860);
FORCEPROP 2 LASTPIN (450 4800) $PN 122
J 0
(460 4810);
DISPLAY 0.617021 (460 4810);
PAINT ORANGE (460 4810);
FORCEPROP 2 LASTPIN (450 4750) $PN 110
J 0
(460 4760);
DISPLAY 0.617021 (460 4760);
PAINT ORANGE (460 4760);
FORCEPROP 2 LASTPIN (450 4700) $PN 111
J 0
(460 4710);
DISPLAY 0.617021 (460 4710);
PAINT ORANGE (460 4710);
FORCEPROP 2 LASTPIN (450 4650) $PN 99
J 0
(460 4660);
DISPLAY 0.617021 (460 4660);
PAINT ORANGE (460 4660);
FORCEPROP 2 LASTPIN (450 4600) $PN 100
J 0
(460 4610);
DISPLAY 0.617021 (460 4610);
PAINT ORANGE (460 4610);
FORCEPROP 2 LASTPIN (450 4550) $PN 40
J 0
(460 4560);
DISPLAY 0.617021 (460 4560);
PAINT ORANGE (460 4560);
FORCEPROP 2 LASTPIN (450 4500) $PN 41
J 0
(460 4510);
DISPLAY 0.617021 (460 4510);
PAINT ORANGE (460 4510);
FORCEPROP 2 LASTPIN (450 4450) $PN 29
J 0
(460 4460);
DISPLAY 0.617021 (460 4460);
PAINT ORANGE (460 4460);
FORCEPROP 2 LASTPIN (450 4400) $PN 30
J 0
(460 4410);
DISPLAY 0.617021 (460 4410);
PAINT ORANGE (460 4410);
FORCEPROP 2 LASTPIN (450 4350) $PN 18
J 0
(460 4360);
DISPLAY 0.617021 (460 4360);
PAINT ORANGE (460 4360);
FORCEPROP 2 LASTPIN (450 4300) $PN 19
J 0
(460 4310);
DISPLAY 0.617021 (460 4310);
PAINT ORANGE (460 4310);
FORCEPROP 2 LASTPIN (450 4250) $PN 7
J 0
(460 4260);
DISPLAY 0.617021 (460 4260);
PAINT ORANGE (460 4260);
FORCEPROP 2 LASTPIN (450 4200) $PN 8
J 0
(460 4210);
DISPLAY 0.617021 (460 4210);
PAINT ORANGE (460 4210);
FORCEPROP 2 LASTPIN (450 4150) $PN 197
J 0
(460 4160);
DISPLAY 0.617021 (460 4160);
PAINT ORANGE (460 4160);
FORCEPROP 2 LASTPIN (450 4100) $PN 196
J 0
(460 4110);
DISPLAY 0.617021 (460 4110);
PAINT ORANGE (460 4110);
FORCEPROP 2 LASTPIN (450 4050) $PN 278
J 0
(460 4060);
DISPLAY 0.617021 (460 4060);
PAINT ORANGE (460 4060);
FORCEPROP 2 LASTPIN (450 4000) $PN 277
J 0
(460 4010);
DISPLAY 0.617021 (460 4010);
PAINT ORANGE (460 4010);
FORCEPROP 2 LASTPIN (450 3950) $PN 267
J 0
(460 3960);
DISPLAY 0.617021 (460 3960);
PAINT ORANGE (460 3960);
FORCEPROP 2 LASTPIN (450 3900) $PN 266
J 0
(460 3910);
DISPLAY 0.617021 (460 3910);
PAINT ORANGE (460 3910);
FORCEPROP 2 LASTPIN (450 3850) $PN 256
J 0
(460 3860);
DISPLAY 0.617021 (460 3860);
PAINT ORANGE (460 3860);
FORCEPROP 2 LASTPIN (450 3800) $PN 255
J 0
(460 3810);
DISPLAY 0.617021 (460 3810);
PAINT ORANGE (460 3810);
FORCEPROP 2 LASTPIN (450 3750) $PN 245
J 0
(460 3760);
DISPLAY 0.617021 (460 3760);
PAINT ORANGE (460 3760);
FORCEPROP 2 LASTPIN (450 3700) $PN 244
J 0
(460 3710);
DISPLAY 0.617021 (460 3710);
PAINT ORANGE (460 3710);
FORCEPROP 2 LASTPIN (450 3650) $PN 186
J 0
(460 3660);
DISPLAY 0.617021 (460 3660);
PAINT ORANGE (460 3660);
FORCEPROP 2 LASTPIN (450 3600) $PN 185
J 0
(460 3610);
DISPLAY 0.617021 (460 3610);
PAINT ORANGE (460 3610);
FORCEPROP 2 LASTPIN (450 3550) $PN 175
J 0
(460 3560);
DISPLAY 0.617021 (460 3560);
PAINT ORANGE (460 3560);
FORCEPROP 2 LASTPIN (450 3500) $PN 174
J 0
(460 3510);
DISPLAY 0.617021 (460 3510);
PAINT ORANGE (460 3510);
FORCEPROP 2 LASTPIN (450 3450) $PN 164
J 0
(460 3460);
DISPLAY 0.617021 (460 3460);
PAINT ORANGE (460 3460);
FORCEPROP 2 LASTPIN (450 3400) $PN 163
J 0
(460 3410);
DISPLAY 0.617021 (460 3410);
PAINT ORANGE (460 3410);
FORCEPROP 2 LASTPIN (450 3350) $PN 153
J 0
(460 3360);
DISPLAY 0.617021 (460 3360);
PAINT ORANGE (460 3360);
FORCEPROP 2 LASTPIN (450 3300) $PN 152
J 0
(460 3310);
DISPLAY 0.617021 (460 3310);
PAINT ORANGE (460 3310);
FORCEPROP 1 LAST PACK_TYPE PIP
J 0
(-400 5350);
PAINT SKYBLUE (-400 5350);
DISPLAY INVISIBLE (-400 5350);
FORCEPROP 2 LAST BOM_COST MEM
J 0
(0 4200);
PAINT ORANGE (0 4200);
DISPLAY INVISIBLE (0 4200);
FORCEPROP 2 LAST CDS_LIB mstr_sconn
J 0
(0 4200);
PAINT ORANGE (0 4200);
DISPLAY INVISIBLE (0 4200);
FORCEPROP 2 LAST SEC_TYPE PIP
J 0
(-400 5350);
DISPLAY 1.021277 (-400 5350);
PAINT ORANGE (-400 5350);
DISPLAY INVISIBLE (-400 5350);
FORCEPROP 2 LAST SEC 2
J 0
(-400 5350);
DISPLAY 0.680851 (-400 5350);
PAINT MONO (-400 5350);
DISPLAY INVISIBLE (-400 5350);
FORCEPROP 2 LAST CDS_LOCATION J1G1
J 0
(-400 5300);
DISPLAY 0.617021 (-400 5300);
PAINT AQUA (-400 5300);
DISPLAY INVISIBLE (-400 5300);
FORCEPROP 1 LAST PATH I66
J 0
(0 5250);
PAINT GREEN (0 5250);
DISPLAY INVISIBLE (0 5250);
FORCEPROP 2 LAST ROOM DDR4_CH_G
J 0
(0 4200);
PAINT ORANGE (0 4200);
DISPLAY INVISIBLE (0 4200);
FORCEADD TAP..6
R 2
(-1625 3325);
FORCEPROP 3 LASTPIN (-1675 3325) SIG_NAME M_G_DQ<40>
J 0
(-1665 3335);
DISPLAY 0.659574 (-1665 3335);
PAINT MONO (-1665 3335);
DISPLAY INVISIBLE (-1665 3335);
FORCEPROP 1 LASTPIN (-1675 3325) BN 40
J 2
(-1625 3335);
DISPLAY 0.617021 (-1625 3335);
PAINT PINK (-1625 3335);
FORCEPROP 2 LAST CDS_LIB mstr_standard
J 2
(-1625 3325);
DISPLAY 0.787234 (-1625 3325);
PAINT MONO (-1625 3325);
DISPLAY INVISIBLE (-1625 3325);
FORCEPROP 1 LAST BODY_TYPE PLUMBING
J 2
(-1625 3275);
DISPLAY 1.234043 (-1625 3275);
PAINT GREEN (-1625 3275);
DISPLAY INVISIBLE (-1625 3275);
FORCEPROP 1 LAST HDL_TAP TRUE
J 2
(-1950 3200);
DISPLAY 1.234043 (-1950 3200);
PAINT GREEN (-1950 3200);
DISPLAY INVISIBLE (-1950 3200);
FORCEPROP 1 LAST PATH I67
J 2
(-1625 3325);
DISPLAY 0.936170 (-1625 3325);
PAINT GREEN (-1625 3325);
DISPLAY INVISIBLE (-1625 3325);
FORCEADD TAP..6
R 2
(-1625 3375);
FORCEPROP 3 LASTPIN (-1675 3375) SIG_NAME M_G_DQ<43>
J 0
(-1665 3385);
DISPLAY 0.659574 (-1665 3385);
PAINT MONO (-1665 3385);
DISPLAY INVISIBLE (-1665 3385);
FORCEPROP 1 LASTPIN (-1675 3375) BN 43
J 2
(-1625 3385);
DISPLAY 0.617021 (-1625 3385);
PAINT PINK (-1625 3385);
FORCEPROP 2 LAST CDS_LIB mstr_standard
J 2
(-1625 3375);
DISPLAY 0.787234 (-1625 3375);
PAINT MONO (-1625 3375);
DISPLAY INVISIBLE (-1625 3375);
FORCEPROP 1 LAST BODY_TYPE PLUMBING
J 2
(-1625 3325);
DISPLAY 1.234043 (-1625 3325);
PAINT GREEN (-1625 3325);
DISPLAY INVISIBLE (-1625 3325);
FORCEPROP 1 LAST HDL_TAP TRUE
J 2
(-1950 3250);
DISPLAY 1.234043 (-1950 3250);
PAINT GREEN (-1950 3250);
DISPLAY INVISIBLE (-1950 3250);
FORCEPROP 1 LAST PATH I68
J 2
(-1625 3375);
DISPLAY 0.936170 (-1625 3375);
PAINT GREEN (-1625 3375);
DISPLAY INVISIBLE (-1625 3375);
FORCEADD TAP..6
R 2
(-1625 3425);
FORCEPROP 3 LASTPIN (-1675 3425) SIG_NAME M_G_DQ<42>
J 0
(-1665 3435);
DISPLAY 0.659574 (-1665 3435);
PAINT MONO (-1665 3435);
DISPLAY INVISIBLE (-1665 3435);
FORCEPROP 1 LASTPIN (-1675 3425) BN 42
J 2
(-1625 3435);
DISPLAY 0.617021 (-1625 3435);
PAINT PINK (-1625 3435);
FORCEPROP 2 LAST CDS_LIB mstr_standard
J 2
(-1625 3425);
DISPLAY 0.787234 (-1625 3425);
PAINT MONO (-1625 3425);
DISPLAY INVISIBLE (-1625 3425);
FORCEPROP 1 LAST BODY_TYPE PLUMBING
J 2
(-1625 3375);
DISPLAY 1.234043 (-1625 3375);
PAINT GREEN (-1625 3375);
DISPLAY INVISIBLE (-1625 3375);
FORCEPROP 1 LAST HDL_TAP TRUE
J 2
(-1950 3300);
DISPLAY 1.234043 (-1950 3300);
PAINT GREEN (-1950 3300);
DISPLAY INVISIBLE (-1950 3300);
FORCEPROP 1 LAST PATH I69
J 2
(-1625 3425);
DISPLAY 0.936170 (-1625 3425);
PAINT GREEN (-1625 3425);
DISPLAY INVISIBLE (-1625 3425);
FORCEADD TAP..6
R 2
(900 4600);
FORCEPROP 3 LASTPIN (850 4600) SIG_NAME M_G_DQS_DN<13>
J 0
(860 4610);
DISPLAY 0.659574 (860 4610);
PAINT MONO (860 4610);
DISPLAY INVISIBLE (860 4610);
FORCEPROP 1 LASTPIN (850 4600) BN 13
J 2
(900 4610);
DISPLAY 0.617021 (900 4610);
PAINT PINK (900 4610);
FORCEPROP 2 LAST CDS_LIB mstr_standard
J 0
(900 4600);
DISPLAY 0.787234 (900 4600);
PAINT MONO (900 4600);
DISPLAY INVISIBLE (900 4600);
FORCEPROP 1 LAST BODY_TYPE PLUMBING
J 2
(900 4550);
DISPLAY 1.234043 (900 4550);
PAINT GREEN (900 4550);
DISPLAY INVISIBLE (900 4550);
FORCEPROP 1 LAST HDL_TAP TRUE
J 2
(575 4475);
DISPLAY 1.234043 (575 4475);
PAINT GREEN (575 4475);
DISPLAY INVISIBLE (575 4475);
FORCEPROP 1 LAST PATH I7
J 2
(900 4600);
DISPLAY 0.936170 (900 4600);
PAINT GREEN (900 4600);
DISPLAY INVISIBLE (900 4600);
FORCEADD TAP..6
R 2
(-1625 3225);
FORCEPROP 3 LASTPIN (-1675 3225) SIG_NAME M_G_DQ<38>
J 0
(-1665 3235);
DISPLAY 0.659574 (-1665 3235);
PAINT MONO (-1665 3235);
DISPLAY INVISIBLE (-1665 3235);
FORCEPROP 1 LASTPIN (-1675 3225) BN 38
J 2
(-1625 3235);
DISPLAY 0.617021 (-1625 3235);
PAINT PINK (-1625 3235);
FORCEPROP 2 LAST CDS_LIB mstr_standard
J 2
(-1625 3225);
DISPLAY 0.787234 (-1625 3225);
PAINT MONO (-1625 3225);
DISPLAY INVISIBLE (-1625 3225);
FORCEPROP 1 LAST BODY_TYPE PLUMBING
J 2
(-1625 3175);
DISPLAY 1.234043 (-1625 3175);
PAINT GREEN (-1625 3175);
DISPLAY INVISIBLE (-1625 3175);
FORCEPROP 1 LAST HDL_TAP TRUE
J 2
(-1950 3100);
DISPLAY 1.234043 (-1950 3100);
PAINT GREEN (-1950 3100);
DISPLAY INVISIBLE (-1950 3100);
FORCEPROP 1 LAST PATH I70
J 2
(-1625 3225);
DISPLAY 0.936170 (-1625 3225);
PAINT GREEN (-1625 3225);
DISPLAY INVISIBLE (-1625 3225);
FORCEADD TAP..6
R 2
(-1625 3275);
FORCEPROP 3 LASTPIN (-1675 3275) SIG_NAME M_G_DQ<41>
J 0
(-1665 3285);
DISPLAY 0.659574 (-1665 3285);
PAINT MONO (-1665 3285);
DISPLAY INVISIBLE (-1665 3285);
FORCEPROP 1 LASTPIN (-1675 3275) BN 41
J 2
(-1625 3285);
DISPLAY 0.617021 (-1625 3285);
PAINT PINK (-1625 3285);
FORCEPROP 2 LAST CDS_LIB mstr_standard
J 2
(-1625 3275);
DISPLAY 0.787234 (-1625 3275);
PAINT MONO (-1625 3275);
DISPLAY INVISIBLE (-1625 3275);
FORCEPROP 1 LAST BODY_TYPE PLUMBING
J 2
(-1625 3225);
DISPLAY 1.234043 (-1625 3225);
PAINT GREEN (-1625 3225);
DISPLAY INVISIBLE (-1625 3225);
FORCEPROP 1 LAST HDL_TAP TRUE
J 2
(-1950 3150);
DISPLAY 1.234043 (-1950 3150);
PAINT GREEN (-1950 3150);
DISPLAY INVISIBLE (-1950 3150);
FORCEPROP 1 LAST PATH I71
J 2
(-1625 3275);
DISPLAY 0.936170 (-1625 3275);
PAINT GREEN (-1625 3275);
DISPLAY INVISIBLE (-1625 3275);
FORCEADD TAP..6
R 2
(-1625 3075);
FORCEPROP 3 LASTPIN (-1675 3075) SIG_NAME M_G_DQ<37>
J 0
(-1665 3085);
DISPLAY 0.659574 (-1665 3085);
PAINT MONO (-1665 3085);
DISPLAY INVISIBLE (-1665 3085);
FORCEPROP 1 LASTPIN (-1675 3075) BN 37
J 2
(-1625 3085);
DISPLAY 0.617021 (-1625 3085);
PAINT PINK (-1625 3085);
FORCEPROP 2 LAST CDS_LIB mstr_standard
J 2
(-1625 3075);
DISPLAY 0.787234 (-1625 3075);
PAINT MONO (-1625 3075);
DISPLAY INVISIBLE (-1625 3075);
FORCEPROP 1 LAST BODY_TYPE PLUMBING
J 2
(-1625 3025);
DISPLAY 1.234043 (-1625 3025);
PAINT GREEN (-1625 3025);
DISPLAY INVISIBLE (-1625 3025);
FORCEPROP 1 LAST HDL_TAP TRUE
J 2
(-1950 2950);
DISPLAY 1.234043 (-1950 2950);
PAINT GREEN (-1950 2950);
DISPLAY INVISIBLE (-1950 2950);
FORCEPROP 1 LAST PATH I72
J 2
(-1625 3075);
DISPLAY 0.936170 (-1625 3075);
PAINT GREEN (-1625 3075);
DISPLAY INVISIBLE (-1625 3075);
FORCEADD TAP..6
R 2
(-1625 3125);
FORCEPROP 3 LASTPIN (-1675 3125) SIG_NAME M_G_DQ<36>
J 0
(-1665 3135);
DISPLAY 0.659574 (-1665 3135);
PAINT MONO (-1665 3135);
DISPLAY INVISIBLE (-1665 3135);
FORCEPROP 1 LASTPIN (-1675 3125) BN 36
J 2
(-1625 3135);
DISPLAY 0.617021 (-1625 3135);
PAINT PINK (-1625 3135);
FORCEPROP 2 LAST CDS_LIB mstr_standard
J 2
(-1625 3125);
DISPLAY 0.787234 (-1625 3125);
PAINT MONO (-1625 3125);
DISPLAY INVISIBLE (-1625 3125);
FORCEPROP 1 LAST BODY_TYPE PLUMBING
J 2
(-1625 3075);
DISPLAY 1.234043 (-1625 3075);
PAINT GREEN (-1625 3075);
DISPLAY INVISIBLE (-1625 3075);
FORCEPROP 1 LAST HDL_TAP TRUE
J 2
(-1950 3000);
DISPLAY 1.234043 (-1950 3000);
PAINT GREEN (-1950 3000);
DISPLAY INVISIBLE (-1950 3000);
FORCEPROP 1 LAST PATH I73
J 2
(-1625 3125);
DISPLAY 0.936170 (-1625 3125);
PAINT GREEN (-1625 3125);
DISPLAY INVISIBLE (-1625 3125);
FORCEADD TAP..6
R 2
(-1625 3175);
FORCEPROP 3 LASTPIN (-1675 3175) SIG_NAME M_G_DQ<39>
J 0
(-1665 3185);
DISPLAY 0.659574 (-1665 3185);
PAINT MONO (-1665 3185);
DISPLAY INVISIBLE (-1665 3185);
FORCEPROP 1 LASTPIN (-1675 3175) BN 39
J 2
(-1625 3185);
DISPLAY 0.617021 (-1625 3185);
PAINT PINK (-1625 3185);
FORCEPROP 2 LAST CDS_LIB mstr_standard
J 2
(-1625 3175);
DISPLAY 0.787234 (-1625 3175);
PAINT MONO (-1625 3175);
DISPLAY INVISIBLE (-1625 3175);
FORCEPROP 1 LAST BODY_TYPE PLUMBING
J 2
(-1625 3125);
DISPLAY 1.234043 (-1625 3125);
PAINT GREEN (-1625 3125);
DISPLAY INVISIBLE (-1625 3125);
FORCEPROP 1 LAST HDL_TAP TRUE
J 2
(-1950 3050);
DISPLAY 1.234043 (-1950 3050);
PAINT GREEN (-1950 3050);
DISPLAY INVISIBLE (-1950 3050);
FORCEPROP 1 LAST PATH I74
J 2
(-1625 3175);
DISPLAY 0.936170 (-1625 3175);
PAINT GREEN (-1625 3175);
DISPLAY INVISIBLE (-1625 3175);
FORCEADD TAP..6
R 2
(-1625 2975);
FORCEPROP 3 LASTPIN (-1675 2975) SIG_NAME M_G_DQ<35>
J 0
(-1665 2985);
DISPLAY 0.659574 (-1665 2985);
PAINT MONO (-1665 2985);
DISPLAY INVISIBLE (-1665 2985);
FORCEPROP 1 LASTPIN (-1675 2975) BN 35
J 2
(-1625 2985);
DISPLAY 0.617021 (-1625 2985);
PAINT PINK (-1625 2985);
FORCEPROP 2 LAST CDS_LIB mstr_standard
J 2
(-1625 2975);
DISPLAY 0.787234 (-1625 2975);
PAINT MONO (-1625 2975);
DISPLAY INVISIBLE (-1625 2975);
FORCEPROP 1 LAST BODY_TYPE PLUMBING
J 2
(-1625 2925);
DISPLAY 1.234043 (-1625 2925);
PAINT GREEN (-1625 2925);
DISPLAY INVISIBLE (-1625 2925);
FORCEPROP 1 LAST HDL_TAP TRUE
J 2
(-1950 2850);
DISPLAY 1.234043 (-1950 2850);
PAINT GREEN (-1950 2850);
DISPLAY INVISIBLE (-1950 2850);
FORCEPROP 1 LAST PATH I75
J 2
(-1625 2975);
DISPLAY 0.936170 (-1625 2975);
PAINT GREEN (-1625 2975);
DISPLAY INVISIBLE (-1625 2975);
FORCEADD TAP..6
R 2
(-1625 3025);
FORCEPROP 3 LASTPIN (-1675 3025) SIG_NAME M_G_DQ<34>
J 0
(-1665 3035);
DISPLAY 0.659574 (-1665 3035);
PAINT MONO (-1665 3035);
DISPLAY INVISIBLE (-1665 3035);
FORCEPROP 1 LASTPIN (-1675 3025) BN 34
J 2
(-1625 3035);
DISPLAY 0.617021 (-1625 3035);
PAINT PINK (-1625 3035);
FORCEPROP 2 LAST CDS_LIB mstr_standard
J 2
(-1625 3025);
DISPLAY 0.787234 (-1625 3025);
PAINT MONO (-1625 3025);
DISPLAY INVISIBLE (-1625 3025);
FORCEPROP 1 LAST BODY_TYPE PLUMBING
J 2
(-1625 2975);
DISPLAY 1.234043 (-1625 2975);
PAINT GREEN (-1625 2975);
DISPLAY INVISIBLE (-1625 2975);
FORCEPROP 1 LAST HDL_TAP TRUE
J 2
(-1950 2900);
DISPLAY 1.234043 (-1950 2900);
PAINT GREEN (-1950 2900);
DISPLAY INVISIBLE (-1950 2900);
FORCEPROP 1 LAST PATH I76
J 2
(-1625 3025);
DISPLAY 0.936170 (-1625 3025);
PAINT GREEN (-1625 3025);
DISPLAY INVISIBLE (-1625 3025);
FORCEADD TAP..6
R 2
(-1625 2825);
FORCEPROP 3 LASTPIN (-1675 2825) SIG_NAME M_G_DQ<30>
J 0
(-1665 2835);
DISPLAY 0.659574 (-1665 2835);
PAINT MONO (-1665 2835);
DISPLAY INVISIBLE (-1665 2835);
FORCEPROP 1 LASTPIN (-1675 2825) BN 30
J 2
(-1625 2835);
DISPLAY 0.617021 (-1625 2835);
PAINT PINK (-1625 2835);
FORCEPROP 2 LAST CDS_LIB mstr_standard
J 2
(-1625 2825);
DISPLAY 0.787234 (-1625 2825);
PAINT MONO (-1625 2825);
DISPLAY INVISIBLE (-1625 2825);
FORCEPROP 1 LAST BODY_TYPE PLUMBING
J 2
(-1625 2775);
DISPLAY 1.234043 (-1625 2775);
PAINT GREEN (-1625 2775);
DISPLAY INVISIBLE (-1625 2775);
FORCEPROP 1 LAST HDL_TAP TRUE
J 2
(-1950 2700);
DISPLAY 1.234043 (-1950 2700);
PAINT GREEN (-1950 2700);
DISPLAY INVISIBLE (-1950 2700);
FORCEPROP 1 LAST PATH I77
J 2
(-1625 2825);
DISPLAY 0.936170 (-1625 2825);
PAINT GREEN (-1625 2825);
DISPLAY INVISIBLE (-1625 2825);
FORCEADD TAP..6
R 2
(-1625 2875);
FORCEPROP 3 LASTPIN (-1675 2875) SIG_NAME M_G_DQ<33>
J 0
(-1665 2885);
DISPLAY 0.659574 (-1665 2885);
PAINT MONO (-1665 2885);
DISPLAY INVISIBLE (-1665 2885);
FORCEPROP 1 LASTPIN (-1675 2875) BN 33
J 2
(-1625 2885);
DISPLAY 0.617021 (-1625 2885);
PAINT PINK (-1625 2885);
FORCEPROP 2 LAST CDS_LIB mstr_standard
J 2
(-1625 2875);
DISPLAY 0.787234 (-1625 2875);
PAINT MONO (-1625 2875);
DISPLAY INVISIBLE (-1625 2875);
FORCEPROP 1 LAST BODY_TYPE PLUMBING
J 2
(-1625 2825);
DISPLAY 1.234043 (-1625 2825);
PAINT GREEN (-1625 2825);
DISPLAY INVISIBLE (-1625 2825);
FORCEPROP 1 LAST HDL_TAP TRUE
J 2
(-1950 2750);
DISPLAY 1.234043 (-1950 2750);
PAINT GREEN (-1950 2750);
DISPLAY INVISIBLE (-1950 2750);
FORCEPROP 1 LAST PATH I78
J 2
(-1625 2875);
DISPLAY 0.936170 (-1625 2875);
PAINT GREEN (-1625 2875);
DISPLAY INVISIBLE (-1625 2875);
FORCEADD TAP..6
R 2
(-1625 2925);
FORCEPROP 3 LASTPIN (-1675 2925) SIG_NAME M_G_DQ<32>
J 0
(-1665 2935);
DISPLAY 0.659574 (-1665 2935);
PAINT MONO (-1665 2935);
DISPLAY INVISIBLE (-1665 2935);
FORCEPROP 1 LASTPIN (-1675 2925) BN 32
J 2
(-1625 2935);
DISPLAY 0.617021 (-1625 2935);
PAINT PINK (-1625 2935);
FORCEPROP 2 LAST CDS_LIB mstr_standard
J 2
(-1625 2925);
DISPLAY 0.787234 (-1625 2925);
PAINT MONO (-1625 2925);
DISPLAY INVISIBLE (-1625 2925);
FORCEPROP 1 LAST BODY_TYPE PLUMBING
J 2
(-1625 2875);
DISPLAY 1.234043 (-1625 2875);
PAINT GREEN (-1625 2875);
DISPLAY INVISIBLE (-1625 2875);
FORCEPROP 1 LAST HDL_TAP TRUE
J 2
(-1950 2800);
DISPLAY 1.234043 (-1950 2800);
PAINT GREEN (-1950 2800);
DISPLAY INVISIBLE (-1950 2800);
FORCEPROP 1 LAST PATH I79
J 2
(-1625 2925);
DISPLAY 0.936170 (-1625 2925);
PAINT GREEN (-1625 2925);
DISPLAY INVISIBLE (-1625 2925);
FORCEADD TAP..6
R 2
(900 4700);
FORCEPROP 3 LASTPIN (850 4700) SIG_NAME M_G_DQS_DN<14>
J 0
(860 4710);
DISPLAY 0.659574 (860 4710);
PAINT MONO (860 4710);
DISPLAY INVISIBLE (860 4710);
FORCEPROP 1 LASTPIN (850 4700) BN 14
J 2
(900 4710);
DISPLAY 0.617021 (900 4710);
PAINT PINK (900 4710);
FORCEPROP 2 LAST CDS_LIB mstr_standard
J 0
(900 4700);
DISPLAY 0.787234 (900 4700);
PAINT MONO (900 4700);
DISPLAY INVISIBLE (900 4700);
FORCEPROP 1 LAST BODY_TYPE PLUMBING
J 2
(900 4650);
DISPLAY 1.234043 (900 4650);
PAINT GREEN (900 4650);
DISPLAY INVISIBLE (900 4650);
FORCEPROP 1 LAST HDL_TAP TRUE
J 2
(575 4575);
DISPLAY 1.234043 (575 4575);
PAINT GREEN (575 4575);
DISPLAY INVISIBLE (575 4575);
FORCEPROP 1 LAST PATH I8
J 2
(900 4700);
DISPLAY 0.936170 (900 4700);
PAINT GREEN (900 4700);
DISPLAY INVISIBLE (900 4700);
FORCEADD TAP..6
R 2
(-1625 2775);
FORCEPROP 3 LASTPIN (-1675 2775) SIG_NAME M_G_DQ<31>
J 0
(-1665 2785);
DISPLAY 0.659574 (-1665 2785);
PAINT MONO (-1665 2785);
DISPLAY INVISIBLE (-1665 2785);
FORCEPROP 1 LASTPIN (-1675 2775) BN 31
J 2
(-1625 2785);
DISPLAY 0.617021 (-1625 2785);
PAINT PINK (-1625 2785);
FORCEPROP 2 LAST CDS_LIB mstr_standard
J 2
(-1625 2775);
DISPLAY 0.787234 (-1625 2775);
PAINT MONO (-1625 2775);
DISPLAY INVISIBLE (-1625 2775);
FORCEPROP 1 LAST BODY_TYPE PLUMBING
J 2
(-1625 2725);
DISPLAY 1.234043 (-1625 2725);
PAINT GREEN (-1625 2725);
DISPLAY INVISIBLE (-1625 2725);
FORCEPROP 1 LAST HDL_TAP TRUE
J 2
(-1950 2650);
DISPLAY 1.234043 (-1950 2650);
PAINT GREEN (-1950 2650);
DISPLAY INVISIBLE (-1950 2650);
FORCEPROP 1 LAST PATH I80
J 2
(-1625 2775);
DISPLAY 0.936170 (-1625 2775);
PAINT GREEN (-1625 2775);
DISPLAY INVISIBLE (-1625 2775);
FORCEADD TAP..6
R 2
(-1625 2725);
FORCEPROP 3 LASTPIN (-1675 2725) SIG_NAME M_G_DQ<28>
J 0
(-1665 2735);
DISPLAY 0.659574 (-1665 2735);
PAINT MONO (-1665 2735);
DISPLAY INVISIBLE (-1665 2735);
FORCEPROP 1 LASTPIN (-1675 2725) BN 28
J 2
(-1625 2735);
DISPLAY 0.617021 (-1625 2735);
PAINT PINK (-1625 2735);
FORCEPROP 2 LAST CDS_LIB mstr_standard
J 2
(-1625 2725);
DISPLAY 0.787234 (-1625 2725);
PAINT MONO (-1625 2725);
DISPLAY INVISIBLE (-1625 2725);
FORCEPROP 1 LAST BODY_TYPE PLUMBING
J 2
(-1625 2675);
DISPLAY 1.234043 (-1625 2675);
PAINT GREEN (-1625 2675);
DISPLAY INVISIBLE (-1625 2675);
FORCEPROP 1 LAST HDL_TAP TRUE
J 2
(-1950 2600);
DISPLAY 1.234043 (-1950 2600);
PAINT GREEN (-1950 2600);
DISPLAY INVISIBLE (-1950 2600);
FORCEPROP 1 LAST PATH I81
J 2
(-1625 2725);
DISPLAY 0.936170 (-1625 2725);
PAINT GREEN (-1625 2725);
DISPLAY INVISIBLE (-1625 2725);
FORCEADD TAP..6
R 2
(-1625 2575);
FORCEPROP 3 LASTPIN (-1675 2575) SIG_NAME M_G_DQ<27>
J 0
(-1665 2585);
DISPLAY 0.659574 (-1665 2585);
PAINT MONO (-1665 2585);
DISPLAY INVISIBLE (-1665 2585);
FORCEPROP 1 LASTPIN (-1675 2575) BN 27
J 2
(-1625 2585);
DISPLAY 0.617021 (-1625 2585);
PAINT PINK (-1625 2585);
FORCEPROP 2 LAST CDS_LIB mstr_standard
J 2
(-1625 2575);
DISPLAY 0.787234 (-1625 2575);
PAINT MONO (-1625 2575);
DISPLAY INVISIBLE (-1625 2575);
FORCEPROP 1 LAST BODY_TYPE PLUMBING
J 2
(-1625 2525);
DISPLAY 1.234043 (-1625 2525);
PAINT GREEN (-1625 2525);
DISPLAY INVISIBLE (-1625 2525);
FORCEPROP 1 LAST HDL_TAP TRUE
J 2
(-1950 2450);
DISPLAY 1.234043 (-1950 2450);
PAINT GREEN (-1950 2450);
DISPLAY INVISIBLE (-1950 2450);
FORCEPROP 1 LAST PATH I82
J 2
(-1625 2575);
DISPLAY 0.936170 (-1625 2575);
PAINT GREEN (-1625 2575);
DISPLAY INVISIBLE (-1625 2575);
FORCEADD TAP..6
R 2
(-1625 2675);
FORCEPROP 3 LASTPIN (-1675 2675) SIG_NAME M_G_DQ<29>
J 0
(-1665 2685);
DISPLAY 0.659574 (-1665 2685);
PAINT MONO (-1665 2685);
DISPLAY INVISIBLE (-1665 2685);
FORCEPROP 1 LASTPIN (-1675 2675) BN 29
J 2
(-1625 2685);
DISPLAY 0.617021 (-1625 2685);
PAINT PINK (-1625 2685);
FORCEPROP 2 LAST CDS_LIB mstr_standard
J 2
(-1625 2675);
DISPLAY 0.787234 (-1625 2675);
PAINT MONO (-1625 2675);
DISPLAY INVISIBLE (-1625 2675);
FORCEPROP 1 LAST BODY_TYPE PLUMBING
J 2
(-1625 2625);
DISPLAY 1.234043 (-1625 2625);
PAINT GREEN (-1625 2625);
DISPLAY INVISIBLE (-1625 2625);
FORCEPROP 1 LAST HDL_TAP TRUE
J 2
(-1950 2550);
DISPLAY 1.234043 (-1950 2550);
PAINT GREEN (-1950 2550);
DISPLAY INVISIBLE (-1950 2550);
FORCEPROP 1 LAST PATH I83
J 2
(-1625 2675);
DISPLAY 0.936170 (-1625 2675);
PAINT GREEN (-1625 2675);
DISPLAY INVISIBLE (-1625 2675);
FORCEADD TAP..6
R 2
(-1625 2625);
FORCEPROP 3 LASTPIN (-1675 2625) SIG_NAME M_G_DQ<26>
J 0
(-1665 2635);
DISPLAY 0.659574 (-1665 2635);
PAINT MONO (-1665 2635);
DISPLAY INVISIBLE (-1665 2635);
FORCEPROP 1 LASTPIN (-1675 2625) BN 26
J 2
(-1625 2635);
DISPLAY 0.617021 (-1625 2635);
PAINT PINK (-1625 2635);
FORCEPROP 2 LAST CDS_LIB mstr_standard
J 2
(-1625 2625);
DISPLAY 0.787234 (-1625 2625);
PAINT MONO (-1625 2625);
DISPLAY INVISIBLE (-1625 2625);
FORCEPROP 1 LAST BODY_TYPE PLUMBING
J 2
(-1625 2575);
DISPLAY 1.234043 (-1625 2575);
PAINT GREEN (-1625 2575);
DISPLAY INVISIBLE (-1625 2575);
FORCEPROP 1 LAST HDL_TAP TRUE
J 2
(-1950 2500);
DISPLAY 1.234043 (-1950 2500);
PAINT GREEN (-1950 2500);
DISPLAY INVISIBLE (-1950 2500);
FORCEPROP 1 LAST PATH I84
J 2
(-1625 2625);
DISPLAY 0.936170 (-1625 2625);
PAINT GREEN (-1625 2625);
DISPLAY INVISIBLE (-1625 2625);
FORCEADD TAP..6
R 2
(-1625 2475);
FORCEPROP 3 LASTPIN (-1675 2475) SIG_NAME M_G_DQ<25>
J 0
(-1665 2485);
DISPLAY 0.659574 (-1665 2485);
PAINT MONO (-1665 2485);
DISPLAY INVISIBLE (-1665 2485);
FORCEPROP 1 LASTPIN (-1675 2475) BN 25
J 2
(-1625 2485);
DISPLAY 0.617021 (-1625 2485);
PAINT PINK (-1625 2485);
FORCEPROP 2 LAST CDS_LIB mstr_standard
J 2
(-1625 2475);
DISPLAY 0.787234 (-1625 2475);
PAINT MONO (-1625 2475);
DISPLAY INVISIBLE (-1625 2475);
FORCEPROP 1 LAST BODY_TYPE PLUMBING
J 2
(-1625 2425);
DISPLAY 1.234043 (-1625 2425);
PAINT GREEN (-1625 2425);
DISPLAY INVISIBLE (-1625 2425);
FORCEPROP 1 LAST HDL_TAP TRUE
J 2
(-1950 2350);
DISPLAY 1.234043 (-1950 2350);
PAINT GREEN (-1950 2350);
DISPLAY INVISIBLE (-1950 2350);
FORCEPROP 1 LAST PATH I85
J 2
(-1625 2475);
DISPLAY 0.936170 (-1625 2475);
PAINT GREEN (-1625 2475);
DISPLAY INVISIBLE (-1625 2475);
FORCEADD TAP..6
R 2
(-1625 2525);
FORCEPROP 3 LASTPIN (-1675 2525) SIG_NAME M_G_DQ<24>
J 0
(-1665 2535);
DISPLAY 0.659574 (-1665 2535);
PAINT MONO (-1665 2535);
DISPLAY INVISIBLE (-1665 2535);
FORCEPROP 1 LASTPIN (-1675 2525) BN 24
J 2
(-1625 2535);
DISPLAY 0.617021 (-1625 2535);
PAINT PINK (-1625 2535);
FORCEPROP 2 LAST CDS_LIB mstr_standard
J 2
(-1625 2525);
DISPLAY 0.787234 (-1625 2525);
PAINT MONO (-1625 2525);
DISPLAY INVISIBLE (-1625 2525);
FORCEPROP 1 LAST BODY_TYPE PLUMBING
J 2
(-1625 2475);
DISPLAY 1.234043 (-1625 2475);
PAINT GREEN (-1625 2475);
DISPLAY INVISIBLE (-1625 2475);
FORCEPROP 1 LAST HDL_TAP TRUE
J 2
(-1950 2400);
DISPLAY 1.234043 (-1950 2400);
PAINT GREEN (-1950 2400);
DISPLAY INVISIBLE (-1950 2400);
FORCEPROP 1 LAST PATH I86
J 2
(-1625 2525);
DISPLAY 0.936170 (-1625 2525);
PAINT GREEN (-1625 2525);
DISPLAY INVISIBLE (-1625 2525);
FORCEADD TAP..6
R 2
(-1625 2325);
FORCEPROP 3 LASTPIN (-1675 2325) SIG_NAME M_G_DQ<20>
J 0
(-1665 2335);
DISPLAY 0.659574 (-1665 2335);
PAINT MONO (-1665 2335);
DISPLAY INVISIBLE (-1665 2335);
FORCEPROP 1 LASTPIN (-1675 2325) BN 20
J 2
(-1625 2335);
DISPLAY 0.617021 (-1625 2335);
PAINT PINK (-1625 2335);
FORCEPROP 2 LAST CDS_LIB mstr_standard
J 2
(-1625 2325);
DISPLAY 0.787234 (-1625 2325);
PAINT MONO (-1625 2325);
DISPLAY INVISIBLE (-1625 2325);
FORCEPROP 1 LAST BODY_TYPE PLUMBING
J 2
(-1625 2275);
DISPLAY 1.234043 (-1625 2275);
PAINT GREEN (-1625 2275);
DISPLAY INVISIBLE (-1625 2275);
FORCEPROP 1 LAST HDL_TAP TRUE
J 2
(-1950 2200);
DISPLAY 1.234043 (-1950 2200);
PAINT GREEN (-1950 2200);
DISPLAY INVISIBLE (-1950 2200);
FORCEPROP 1 LAST PATH I87
J 2
(-1625 2325);
DISPLAY 0.936170 (-1625 2325);
PAINT GREEN (-1625 2325);
DISPLAY INVISIBLE (-1625 2325);
FORCEADD TAP..6
R 2
(-1625 2425);
FORCEPROP 3 LASTPIN (-1675 2425) SIG_NAME M_G_DQ<22>
J 0
(-1665 2435);
DISPLAY 0.659574 (-1665 2435);
PAINT MONO (-1665 2435);
DISPLAY INVISIBLE (-1665 2435);
FORCEPROP 1 LASTPIN (-1675 2425) BN 22
J 2
(-1625 2435);
DISPLAY 0.617021 (-1625 2435);
PAINT PINK (-1625 2435);
FORCEPROP 2 LAST CDS_LIB mstr_standard
J 2
(-1625 2425);
DISPLAY 0.787234 (-1625 2425);
PAINT MONO (-1625 2425);
DISPLAY INVISIBLE (-1625 2425);
FORCEPROP 1 LAST BODY_TYPE PLUMBING
J 2
(-1625 2375);
DISPLAY 1.234043 (-1625 2375);
PAINT GREEN (-1625 2375);
DISPLAY INVISIBLE (-1625 2375);
FORCEPROP 1 LAST HDL_TAP TRUE
J 2
(-1950 2300);
DISPLAY 1.234043 (-1950 2300);
PAINT GREEN (-1950 2300);
DISPLAY INVISIBLE (-1950 2300);
FORCEPROP 1 LAST PATH I88
J 2
(-1625 2425);
DISPLAY 0.936170 (-1625 2425);
PAINT GREEN (-1625 2425);
DISPLAY INVISIBLE (-1625 2425);
FORCEADD TAP..6
R 2
(-1625 2375);
FORCEPROP 3 LASTPIN (-1675 2375) SIG_NAME M_G_DQ<23>
J 0
(-1665 2385);
DISPLAY 0.659574 (-1665 2385);
PAINT MONO (-1665 2385);
DISPLAY INVISIBLE (-1665 2385);
FORCEPROP 1 LASTPIN (-1675 2375) BN 23
J 2
(-1625 2385);
DISPLAY 0.617021 (-1625 2385);
PAINT PINK (-1625 2385);
FORCEPROP 2 LAST CDS_LIB mstr_standard
J 2
(-1625 2375);
DISPLAY 0.787234 (-1625 2375);
PAINT MONO (-1625 2375);
DISPLAY INVISIBLE (-1625 2375);
FORCEPROP 1 LAST BODY_TYPE PLUMBING
J 2
(-1625 2325);
DISPLAY 1.234043 (-1625 2325);
PAINT GREEN (-1625 2325);
DISPLAY INVISIBLE (-1625 2325);
FORCEPROP 1 LAST HDL_TAP TRUE
J 2
(-1950 2250);
DISPLAY 1.234043 (-1950 2250);
PAINT GREEN (-1950 2250);
DISPLAY INVISIBLE (-1950 2250);
FORCEPROP 1 LAST PATH I89
J 2
(-1625 2375);
DISPLAY 0.936170 (-1625 2375);
PAINT GREEN (-1625 2375);
DISPLAY INVISIBLE (-1625 2375);
FORCEADD TAP..6
R 2
(900 4500);
FORCEPROP 3 LASTPIN (850 4500) SIG_NAME M_G_DQS_DN<12>
J 0
(860 4510);
DISPLAY 0.659574 (860 4510);
PAINT MONO (860 4510);
DISPLAY INVISIBLE (860 4510);
FORCEPROP 1 LASTPIN (850 4500) BN 12
J 2
(900 4510);
DISPLAY 0.617021 (900 4510);
PAINT PINK (900 4510);
FORCEPROP 2 LAST CDS_LIB mstr_standard
J 0
(900 4500);
DISPLAY 0.787234 (900 4500);
PAINT MONO (900 4500);
DISPLAY INVISIBLE (900 4500);
FORCEPROP 1 LAST BODY_TYPE PLUMBING
J 2
(900 4450);
DISPLAY 1.234043 (900 4450);
PAINT GREEN (900 4450);
DISPLAY INVISIBLE (900 4450);
FORCEPROP 1 LAST HDL_TAP TRUE
J 2
(575 4375);
DISPLAY 1.234043 (575 4375);
PAINT GREEN (575 4375);
DISPLAY INVISIBLE (575 4375);
FORCEPROP 1 LAST PATH I9
J 2
(900 4500);
DISPLAY 0.936170 (900 4500);
PAINT GREEN (900 4500);
DISPLAY INVISIBLE (900 4500);
FORCEADD TAP..6
R 2
(-1625 2275);
FORCEPROP 3 LASTPIN (-1675 2275) SIG_NAME M_G_DQ<21>
J 0
(-1665 2285);
DISPLAY 0.659574 (-1665 2285);
PAINT MONO (-1665 2285);
DISPLAY INVISIBLE (-1665 2285);
FORCEPROP 1 LASTPIN (-1675 2275) BN 21
J 2
(-1625 2285);
DISPLAY 0.617021 (-1625 2285);
PAINT PINK (-1625 2285);
FORCEPROP 2 LAST CDS_LIB mstr_standard
J 2
(-1625 2275);
DISPLAY 0.787234 (-1625 2275);
PAINT MONO (-1625 2275);
DISPLAY INVISIBLE (-1625 2275);
FORCEPROP 1 LAST BODY_TYPE PLUMBING
J 2
(-1625 2225);
DISPLAY 1.234043 (-1625 2225);
PAINT GREEN (-1625 2225);
DISPLAY INVISIBLE (-1625 2225);
FORCEPROP 1 LAST HDL_TAP TRUE
J 2
(-1950 2150);
DISPLAY 1.234043 (-1950 2150);
PAINT GREEN (-1950 2150);
DISPLAY INVISIBLE (-1950 2150);
FORCEPROP 1 LAST PATH I90
J 2
(-1625 2275);
DISPLAY 0.936170 (-1625 2275);
PAINT GREEN (-1625 2275);
DISPLAY INVISIBLE (-1625 2275);
FORCEADD TAP..6
R 2
(-1625 2225);
FORCEPROP 3 LASTPIN (-1675 2225) SIG_NAME M_G_DQ<18>
J 0
(-1665 2235);
DISPLAY 0.659574 (-1665 2235);
PAINT MONO (-1665 2235);
DISPLAY INVISIBLE (-1665 2235);
FORCEPROP 1 LASTPIN (-1675 2225) BN 18
J 2
(-1625 2235);
DISPLAY 0.617021 (-1625 2235);
PAINT PINK (-1625 2235);
FORCEPROP 2 LAST CDS_LIB mstr_standard
J 2
(-1625 2225);
DISPLAY 0.787234 (-1625 2225);
PAINT MONO (-1625 2225);
DISPLAY INVISIBLE (-1625 2225);
FORCEPROP 1 LAST BODY_TYPE PLUMBING
J 2
(-1625 2175);
DISPLAY 1.234043 (-1625 2175);
PAINT GREEN (-1625 2175);
DISPLAY INVISIBLE (-1625 2175);
FORCEPROP 1 LAST HDL_TAP TRUE
J 2
(-1950 2100);
DISPLAY 1.234043 (-1950 2100);
PAINT GREEN (-1950 2100);
DISPLAY INVISIBLE (-1950 2100);
FORCEPROP 1 LAST PATH I91
J 2
(-1625 2225);
DISPLAY 0.936170 (-1625 2225);
PAINT GREEN (-1625 2225);
DISPLAY INVISIBLE (-1625 2225);
FORCEADD TAP..6
R 2
(-1625 2175);
FORCEPROP 3 LASTPIN (-1675 2175) SIG_NAME M_G_DQ<19>
J 0
(-1665 2185);
DISPLAY 0.659574 (-1665 2185);
PAINT MONO (-1665 2185);
DISPLAY INVISIBLE (-1665 2185);
FORCEPROP 1 LASTPIN (-1675 2175) BN 19
J 2
(-1625 2185);
DISPLAY 0.617021 (-1625 2185);
PAINT PINK (-1625 2185);
FORCEPROP 2 LAST CDS_LIB mstr_standard
J 2
(-1625 2175);
DISPLAY 0.787234 (-1625 2175);
PAINT MONO (-1625 2175);
DISPLAY INVISIBLE (-1625 2175);
FORCEPROP 1 LAST BODY_TYPE PLUMBING
J 2
(-1625 2125);
DISPLAY 1.234043 (-1625 2125);
PAINT GREEN (-1625 2125);
DISPLAY INVISIBLE (-1625 2125);
FORCEPROP 1 LAST HDL_TAP TRUE
J 2
(-1950 2050);
DISPLAY 1.234043 (-1950 2050);
PAINT GREEN (-1950 2050);
DISPLAY INVISIBLE (-1950 2050);
FORCEPROP 1 LAST PATH I92
J 2
(-1625 2175);
DISPLAY 0.936170 (-1625 2175);
PAINT GREEN (-1625 2175);
DISPLAY INVISIBLE (-1625 2175);
FORCEADD TAP..6
R 2
(-1625 2125);
FORCEPROP 3 LASTPIN (-1675 2125) SIG_NAME M_G_DQ<16>
J 0
(-1665 2135);
DISPLAY 0.659574 (-1665 2135);
PAINT MONO (-1665 2135);
DISPLAY INVISIBLE (-1665 2135);
FORCEPROP 1 LASTPIN (-1675 2125) BN 16
J 2
(-1625 2135);
DISPLAY 0.617021 (-1625 2135);
PAINT PINK (-1625 2135);
FORCEPROP 2 LAST CDS_LIB mstr_standard
J 2
(-1625 2125);
DISPLAY 0.787234 (-1625 2125);
PAINT MONO (-1625 2125);
DISPLAY INVISIBLE (-1625 2125);
FORCEPROP 1 LAST BODY_TYPE PLUMBING
J 2
(-1625 2075);
DISPLAY 1.234043 (-1625 2075);
PAINT GREEN (-1625 2075);
DISPLAY INVISIBLE (-1625 2075);
FORCEPROP 1 LAST HDL_TAP TRUE
J 2
(-1950 2000);
DISPLAY 1.234043 (-1950 2000);
PAINT GREEN (-1950 2000);
DISPLAY INVISIBLE (-1950 2000);
FORCEPROP 1 LAST PATH I93
J 2
(-1625 2125);
DISPLAY 0.936170 (-1625 2125);
PAINT GREEN (-1625 2125);
DISPLAY INVISIBLE (-1625 2125);
FORCEADD TAP..6
R 2
(-1625 2075);
FORCEPROP 3 LASTPIN (-1675 2075) SIG_NAME M_G_DQ<17>
J 0
(-1665 2085);
DISPLAY 0.659574 (-1665 2085);
PAINT MONO (-1665 2085);
DISPLAY INVISIBLE (-1665 2085);
FORCEPROP 1 LASTPIN (-1675 2075) BN 17
J 2
(-1625 2085);
DISPLAY 0.617021 (-1625 2085);
PAINT PINK (-1625 2085);
FORCEPROP 2 LAST CDS_LIB mstr_standard
J 2
(-1625 2075);
DISPLAY 0.787234 (-1625 2075);
PAINT MONO (-1625 2075);
DISPLAY INVISIBLE (-1625 2075);
FORCEPROP 1 LAST BODY_TYPE PLUMBING
J 2
(-1625 2025);
DISPLAY 1.234043 (-1625 2025);
PAINT GREEN (-1625 2025);
DISPLAY INVISIBLE (-1625 2025);
FORCEPROP 1 LAST HDL_TAP TRUE
J 2
(-1950 1950);
DISPLAY 1.234043 (-1950 1950);
PAINT GREEN (-1950 1950);
DISPLAY INVISIBLE (-1950 1950);
FORCEPROP 1 LAST PATH I94
J 2
(-1625 2075);
DISPLAY 0.936170 (-1625 2075);
PAINT GREEN (-1625 2075);
DISPLAY INVISIBLE (-1625 2075);
FORCEADD TAP..6
R 2
(-1625 2025);
FORCEPROP 3 LASTPIN (-1675 2025) SIG_NAME M_G_DQ<14>
J 0
(-1665 2035);
DISPLAY 0.659574 (-1665 2035);
PAINT MONO (-1665 2035);
DISPLAY INVISIBLE (-1665 2035);
FORCEPROP 1 LASTPIN (-1675 2025) BN 14
J 2
(-1625 2035);
DISPLAY 0.617021 (-1625 2035);
PAINT PINK (-1625 2035);
FORCEPROP 2 LAST CDS_LIB mstr_standard
J 2
(-1625 2025);
DISPLAY 0.787234 (-1625 2025);
PAINT MONO (-1625 2025);
DISPLAY INVISIBLE (-1625 2025);
FORCEPROP 1 LAST BODY_TYPE PLUMBING
J 2
(-1625 1975);
DISPLAY 1.234043 (-1625 1975);
PAINT GREEN (-1625 1975);
DISPLAY INVISIBLE (-1625 1975);
FORCEPROP 1 LAST HDL_TAP TRUE
J 2
(-1950 1900);
DISPLAY 1.234043 (-1950 1900);
PAINT GREEN (-1950 1900);
DISPLAY INVISIBLE (-1950 1900);
FORCEPROP 1 LAST PATH I95
J 2
(-1625 2025);
DISPLAY 0.936170 (-1625 2025);
PAINT GREEN (-1625 2025);
DISPLAY INVISIBLE (-1625 2025);
FORCEADD TAP..6
R 2
(-1625 1975);
FORCEPROP 3 LASTPIN (-1675 1975) SIG_NAME M_G_DQ<15>
J 0
(-1665 1985);
DISPLAY 0.659574 (-1665 1985);
PAINT MONO (-1665 1985);
DISPLAY INVISIBLE (-1665 1985);
FORCEPROP 1 LASTPIN (-1675 1975) BN 15
J 2
(-1625 1985);
DISPLAY 0.617021 (-1625 1985);
PAINT PINK (-1625 1985);
FORCEPROP 2 LAST CDS_LIB mstr_standard
J 2
(-1625 1975);
DISPLAY 0.787234 (-1625 1975);
PAINT MONO (-1625 1975);
DISPLAY INVISIBLE (-1625 1975);
FORCEPROP 1 LAST BODY_TYPE PLUMBING
J 2
(-1625 1925);
DISPLAY 1.234043 (-1625 1925);
PAINT GREEN (-1625 1925);
DISPLAY INVISIBLE (-1625 1925);
FORCEPROP 1 LAST HDL_TAP TRUE
J 2
(-1950 1850);
DISPLAY 1.234043 (-1950 1850);
PAINT GREEN (-1950 1850);
DISPLAY INVISIBLE (-1950 1850);
FORCEPROP 1 LAST PATH I96
J 2
(-1625 1975);
DISPLAY 0.936170 (-1625 1975);
PAINT GREEN (-1625 1975);
DISPLAY INVISIBLE (-1625 1975);
FORCEADD TAP..6
R 2
(-1625 1875);
FORCEPROP 3 LASTPIN (-1675 1875) SIG_NAME M_G_DQ<13>
J 0
(-1665 1885);
DISPLAY 0.659574 (-1665 1885);
PAINT MONO (-1665 1885);
DISPLAY INVISIBLE (-1665 1885);
FORCEPROP 1 LASTPIN (-1675 1875) BN 13
J 2
(-1625 1885);
DISPLAY 0.617021 (-1625 1885);
PAINT PINK (-1625 1885);
FORCEPROP 2 LAST CDS_LIB mstr_standard
J 2
(-1625 1875);
DISPLAY 0.787234 (-1625 1875);
PAINT MONO (-1625 1875);
DISPLAY INVISIBLE (-1625 1875);
FORCEPROP 1 LAST BODY_TYPE PLUMBING
J 2
(-1625 1825);
DISPLAY 1.234043 (-1625 1825);
PAINT GREEN (-1625 1825);
DISPLAY INVISIBLE (-1625 1825);
FORCEPROP 1 LAST HDL_TAP TRUE
J 2
(-1950 1750);
DISPLAY 1.234043 (-1950 1750);
PAINT GREEN (-1950 1750);
DISPLAY INVISIBLE (-1950 1750);
FORCEPROP 1 LAST PATH I97
J 2
(-1625 1875);
DISPLAY 0.936170 (-1625 1875);
PAINT GREEN (-1625 1875);
DISPLAY INVISIBLE (-1625 1875);
FORCEADD TAP..6
R 2
(-1625 1925);
FORCEPROP 3 LASTPIN (-1675 1925) SIG_NAME M_G_DQ<12>
J 0
(-1665 1935);
DISPLAY 0.659574 (-1665 1935);
PAINT MONO (-1665 1935);
DISPLAY INVISIBLE (-1665 1935);
FORCEPROP 1 LASTPIN (-1675 1925) BN 12
J 2
(-1625 1935);
DISPLAY 0.617021 (-1625 1935);
PAINT PINK (-1625 1935);
FORCEPROP 2 LAST CDS_LIB mstr_standard
J 2
(-1625 1925);
DISPLAY 0.787234 (-1625 1925);
PAINT MONO (-1625 1925);
DISPLAY INVISIBLE (-1625 1925);
FORCEPROP 1 LAST BODY_TYPE PLUMBING
J 2
(-1625 1875);
DISPLAY 1.234043 (-1625 1875);
PAINT GREEN (-1625 1875);
DISPLAY INVISIBLE (-1625 1875);
FORCEPROP 1 LAST HDL_TAP TRUE
J 2
(-1950 1800);
DISPLAY 1.234043 (-1950 1800);
PAINT GREEN (-1950 1800);
DISPLAY INVISIBLE (-1950 1800);
FORCEPROP 1 LAST PATH I98
J 2
(-1625 1925);
DISPLAY 0.936170 (-1625 1925);
PAINT GREEN (-1625 1925);
DISPLAY INVISIBLE (-1625 1925);
FORCEADD TAP..6
R 2
(-1625 1825);
FORCEPROP 3 LASTPIN (-1675 1825) SIG_NAME M_G_DQ<10>
J 0
(-1665 1835);
DISPLAY 0.659574 (-1665 1835);
PAINT MONO (-1665 1835);
DISPLAY INVISIBLE (-1665 1835);
FORCEPROP 1 LASTPIN (-1675 1825) BN 10
J 2
(-1625 1835);
DISPLAY 0.617021 (-1625 1835);
PAINT PINK (-1625 1835);
FORCEPROP 2 LAST CDS_LIB mstr_standard
J 2
(-1625 1825);
DISPLAY 0.787234 (-1625 1825);
PAINT MONO (-1625 1825);
DISPLAY INVISIBLE (-1625 1825);
FORCEPROP 1 LAST BODY_TYPE PLUMBING
J 2
(-1625 1775);
DISPLAY 1.234043 (-1625 1775);
PAINT GREEN (-1625 1775);
DISPLAY INVISIBLE (-1625 1775);
FORCEPROP 1 LAST HDL_TAP TRUE
J 2
(-1950 1700);
DISPLAY 1.234043 (-1950 1700);
PAINT GREEN (-1950 1700);
DISPLAY INVISIBLE (-1950 1700);
FORCEPROP 1 LAST PATH I99
J 2
(-1625 1825);
DISPLAY 0.936170 (-1625 1825);
PAINT GREEN (-1625 1825);
DISPLAY INVISIBLE (-1625 1825);
FORCEADD BOM_NOTE..1
(-5050 5125);
FORCEPROP 0 LAST L1 STUFF FOR SKU A & B
J 0
(-5200 5025);
DISPLAY 1.063830 (-5200 5025);
PAINT WHITE (-5200 5025);
FORCEPROP 2 LAST CDS_LIB mstr_symbols
J 0
(-5050 5125);
PAINT ORANGE (-5050 5125);
DISPLAY INVISIBLE (-5050 5125);
FORCEPROP 2 LAST BOM_COST SB
J 0
(-5200 5100);
DISPLAY 1.361702 (-5200 5100);
PAINT ORANGE (-5200 5100);
DISPLAY INVISIBLE (-5200 5100);
FORCEPROP 1 LAST COMMENT_BODY TRUE
J 0
(-5025 5225);
DISPLAY 1.319149 (-5025 5225);
PAINT ORANGE (-5025 5225);
DISPLAY INVISIBLE (-5025 5225);
FORCEPROP 2 LAST ROOM SB_HEADERS
J 0
(-5200 5100);
DISPLAY 1.361702 (-5200 5100);
PAINT ORANGE (-5200 5100);
DISPLAY INVISIBLE (-5200 5100);
FORCEADD INTEL_CORP_BPAGE..1
(2650 375);
FORCEPROP 1 LAST CDS_CON_LAST_MODIFIED Tue Dec 01 11:51:40 2015
J 0
(1225 700);
DISPLAY 0.787234 (1225 700);
PAINT ORANGE (1225 700);
DISPLAY INVISIBLE (1225 700);
FORCEPROP 1 LAST CUSTOM_TXT_CDS <CURRENT_DESIGN_SHEET> OF <TOTAL_DESIGN_SHEETS>
J 0
(2150 400);
PAINT GREEN (2150 400);
FORCEPROP 2 LAST CUSTOM_TXT_CDS <XR_PAGE_TITLE>
J 0
(-5240 5625);
DISPLAY 0.638298 (-5240 5625);
PAINT PINK (-5240 5625);
DISPLAY INVISIBLE (-5240 5625);
FORCEPROP 2 LAST CUSTOM_TXT_CDS <CON_LAST_MODIFIED>
J 0
(1375 700);
DISPLAY 0.851064 (1375 700);
PAINT GREEN (1375 700);
FORCEPROP 1 LAST SCH_ADDRESS3 Santa Clara, CA 95052-8119
J 0
(-1325 400);
DISPLAY 0.617021 (-1325 400);
PAINT GREEN (-1325 400);
FORCEPROP 1 LAST SCH_ADDRESS2 P.O. BOX 58119
J 0
(-1325 450);
DISPLAY 0.617021 (-1325 450);
PAINT GREEN (-1325 450);
FORCEPROP 1 LAST SCH_ADDRESS1 2200 Mission College Blvd.
J 0
(-1325 500);
DISPLAY 0.617021 (-1325 500);
PAINT GREEN (-1325 500);
FORCEPROP 1 LAST SCH_TITLE CPU1 DDR4 CH G DIMM0
J 0
(-5300 425);
DISPLAY 1.212766 (-5300 425);
PAINT WHITE (-5300 425);
FORCEPROP 1 LAST SCH_NUMBER H4694802
J 0
(1350 525);
DISPLAY 1.212766 (1350 525);
PAINT YELLOW (1350 525);
FORCEPROP 1 LAST SCH_DEPT BESD
J 1
(-1800 475);
DISPLAY 1.212766 (-1800 475);
PAINT YELLOW (-1800 475);
FORCEPROP 1 LAST SCH_REV 2.420
J 0
(2400 525);
DISPLAY 0.978723 (2400 525);
PAINT YELLOW (2400 525);
FORCEPROP 2 LAST CDS_LIB mstr_symbols
J 0
(2650 375);
DISPLAY 0.787234 (2650 375);
PAINT MONO (2650 375);
DISPLAY INVISIBLE (2650 375);
FORCEPROP 2 LAST PAGE_BORDER TRUE
J 0
(-5240 5625);
DISPLAY 0.680851 (-5240 5625);
PAINT PINK (-5240 5625);
DISPLAY INVISIBLE (-5240 5625);
FORCEPROP 1 LAST COMMENT_BODY TRUE
J 0
(2660 385);
DISPLAY 0.382979 (2660 385);
PAINT GREEN (2660 385);
DISPLAY INVISIBLE (2660 385);
FORCEPROP 2 LAST CDS_XR_PAGE_TITLE CR-77 : @BASEBOARD_FAB2_LIB.BASEBOARD_FAB2(SCH_1):PAGE77
J 0
(-5240 5625);
DISPLAY 0.638298 (-5240 5625);
PAINT PINK (-5240 5625);
DISPLAY INVISIBLE (-5240 5625);
WIRE 17 -1 (950 4325)(950 4425);
WIRE 17 -1 (950 4225)(950 4325);
WIRE 17 -1 (950 4425)(950 4525);
WIRE 17 -1 (950 4525)(950 4625);
WIRE 17 -1 (950 4125)(950 4225);
WIRE 17 -1 (950 4025)(950 4125);
WIRE 17 -1 (950 4625)(950 4725);
WIRE 17 -1 (950 4725)(950 4825);
WIRE 17 -1 (950 3925)(950 4025);
WIRE 17 -1 (950 3825)(950 3925);
WIRE 17 -1 (950 4825)(950 4925);
WIRE 17 -1 (950 4925)(950 5025);
WIRE 17 -1 (950 3725)(950 3825);
WIRE 17 -1 (950 3625)(950 3725);
WIRE 17 -1 (950 5025)(950 5050);
WIRE 17 -1 (1550 5050)(950 5050);
FORCEPROP 2 LAST SIG_NAME M_G_DQS_DN<17:0>
J 0
(975 5060);
DISPLAY 0.617021 (975 5060);
PAINT ORANGE (975 5060);
WIRE 17 -1 (750 4375)(750 4475);
WIRE 17 -1 (750 4275)(750 4375);
WIRE 17 -1 (750 4475)(750 4575);
WIRE 17 -1 (750 4575)(750 4675);
WIRE 17 -1 (750 4175)(750 4275);
WIRE 17 -1 (750 4075)(750 4175);
WIRE 17 -1 (750 4675)(750 4775);
WIRE 17 -1 (750 4775)(750 4875);
WIRE 17 -1 (750 3975)(750 4075);
WIRE 17 -1 (750 3875)(750 3975);
WIRE 17 -1 (750 4875)(750 4975);
WIRE 17 -1 (750 4975)(750 5075);
WIRE 17 -1 (750 3775)(750 3875);
WIRE 17 -1 (750 3675)(750 3775);
WIRE 17 -1 (750 5075)(750 5100);
WIRE 17 -1 (1550 5100)(750 5100);
FORCEPROP 2 LAST SIG_NAME M_G_DQS_DP<17:0>
J 0
(975 5110);
DISPLAY 0.617021 (975 5110);
PAINT ORANGE (975 5110);
WIRE 17 -1 (950 3525)(950 3625);
WIRE 17 -1 (950 3425)(950 3525);
WIRE 17 -1 (950 3325)(950 3425);
WIRE 17 -1 (750 3575)(750 3675);
WIRE 17 -1 (750 3475)(750 3575);
WIRE 17 -1 (750 3375)(750 3475);
WIRE 17 -1 (-1575 4300)(-1575 4350);
WIRE 17 -1 (-1575 4250)(-1575 4300);
WIRE 17 -1 (-1575 4350)(-1575 4400);
WIRE 17 -1 (-1575 4400)(-1575 4450);
WIRE 17 -1 (-1575 4200)(-1575 4250);
WIRE 17 -1 (-1575 4150)(-1575 4200);
WIRE 17 -1 (-1575 4475)(-1575 4450);
WIRE 17 -1 (-1125 4475)(-1575 4475);
FORCEPROP 2 LAST SIG_NAME M_G_DQ<63:0>
J 0
(-1535 4485);
DISPLAY 0.617021 (-1535 4485);
PAINT ORANGE (-1535 4485);
WIRE 17 -1 (-1575 4100)(-1575 4150);
WIRE 17 -1 (-1575 4050)(-1575 4100);
WIRE 17 -1 (-1575 4000)(-1575 4050);
WIRE 17 -1 (-1575 3950)(-1575 4000);
WIRE 17 -1 (-1575 3900)(-1575 3950);
WIRE 17 -1 (-1575 3850)(-1575 3900);
WIRE 17 -1 (-1575 3800)(-1575 3850);
WIRE 17 -1 (-3175 4200)(-3175 4250);
WIRE 17 -1 (-3175 4150)(-3175 4200);
WIRE 17 -1 (-3175 4250)(-3175 4300);
WIRE 17 -1 (-3175 4300)(-3175 4350);
WIRE 17 -1 (-3175 4100)(-3175 4150);
WIRE 17 -1 (-3175 4050)(-3175 4100);
WIRE 17 -1 (-3175 4350)(-3175 4400);
WIRE 17 -1 (-3175 4400)(-3175 4450);
WIRE 17 -1 (-3175 4000)(-3175 4050);
WIRE 17 -1 (-3175 3950)(-3175 4000);
WIRE 17 -1 (-3175 4450)(-3175 4475);
WIRE 17 -1 (-3725 4475)(-3175 4475);
FORCEPROP 2 LAST SIG_NAME M_G_MA<17:0>
J 0
(-3700 4485);
DISPLAY 0.617021 (-3700 4485);
PAINT ORANGE (-3700 4485);
WIRE 17 -1 (-3175 3900)(-3175 3950);
WIRE 17 -1 (-3175 3850)(-3175 3900);
WIRE 17 -1 (-3175 3800)(-3175 3850);
WIRE 17 -1 (-1575 3700)(-1575 3750);
WIRE 17 -1 (-1575 3650)(-1575 3700);
WIRE 17 -1 (-1575 3750)(-1575 3800);
WIRE 17 -1 (-1575 3600)(-1575 3650);
WIRE 17 -1 (-1575 3550)(-1575 3600);
WIRE 17 -1 (-1575 3500)(-1575 3550);
WIRE 17 -1 (-1575 3450)(-1575 3500);
WIRE 17 -1 (-1575 3400)(-1575 3450);
WIRE 17 -1 (-1575 3350)(-1575 3400);
WIRE 17 -1 (-1575 3300)(-1575 3350);
WIRE 17 -1 (-1575 3250)(-1575 3300);
WIRE 17 -1 (-1575 3200)(-1575 3250);
WIRE 17 -1 (-1575 3150)(-1575 3200);
WIRE 17 -1 (-1575 3100)(-1575 3150);
WIRE 17 -1 (-1575 3050)(-1575 3100);
WIRE 17 -1 (-1575 3000)(-1575 3050);
WIRE 17 -1 (-1575 2950)(-1575 3000);
WIRE 17 -1 (-1575 2900)(-1575 2950);
WIRE 17 -1 (-1575 2850)(-1575 2900);
WIRE 17 -1 (-1575 2800)(-1575 2850);
WIRE 17 -1 (-1575 2750)(-1575 2800);
WIRE 17 -1 (-1575 2700)(-1575 2750);
WIRE 17 -1 (-1575 2650)(-1575 2700);
WIRE 17 -1 (-1575 2600)(-1575 2650);
WIRE 17 -1 (-1575 2550)(-1575 2600);
WIRE 17 -1 (-1575 2500)(-1575 2550);
WIRE 17 -1 (-1575 2450)(-1575 2500);
WIRE 17 -1 (-1575 2400)(-1575 2450);
WIRE 17 -1 (-1575 2350)(-1575 2400);
WIRE 17 -1 (-1575 2300)(-1575 2350);
WIRE 17 -1 (-1575 2250)(-1575 2300);
WIRE 17 -1 (-1575 2200)(-1575 2250);
WIRE 17 -1 (-1575 2150)(-1575 2200);
WIRE 17 -1 (-1575 2100)(-1575 2150);
WIRE 17 -1 (-1575 2050)(-1575 2100);
WIRE 17 -1 (-1575 2000)(-1575 2050);
WIRE 17 -1 (-1575 1950)(-1575 2000);
WIRE 17 -1 (-1575 1900)(-1575 1950);
WIRE 17 -1 (-1575 1850)(-1575 1900);
WIRE 17 -1 (-1575 1800)(-1575 1850);
WIRE 17 -1 (-1575 1750)(-1575 1800);
WIRE 17 -1 (-1575 1700)(-1575 1750);
WIRE 17 -1 (-1575 1650)(-1575 1700);
WIRE 17 -1 (-1575 1600)(-1575 1650);
WIRE 17 -1 (-1575 1550)(-1575 1600);
WIRE 17 -1 (-1575 1500)(-1575 1550);
WIRE 17 -1 (-1575 1450)(-1575 1500);
WIRE 17 -1 (-1575 1400)(-1575 1450);
WIRE 17 -1 (-1575 1350)(-1575 1400);
WIRE 17 -1 (-1575 1300)(-1575 1350);
WIRE 17 -1 (-3375 3250)(-3375 3200);
WIRE 17 -1 (-3375 3250)(-3725 3250);
FORCEPROP 2 LAST SIG_NAME M_G_CLK_DN<3:0>
J 0
(-3725 3260);
DISPLAY 0.617021 (-3725 3260);
PAINT ORANGE (-3725 3260);
WIRE 17 -1 (-3175 3150)(-3175 3250);
WIRE 17 -1 (-3175 3300)(-3175 3250);
WIRE 17 -1 (-3175 3300)(-3725 3300);
FORCEPROP 2 LAST SIG_NAME M_G_CLK_DP<3:0>
J 0
(-3725 3310);
DISPLAY 0.617021 (-3725 3310);
PAINT ORANGE (-3725 3310);
WIRE 17 -1 (-3375 3200)(-3375 3100);
WIRE 17 -1 (-3175 3550)(-3175 3500);
WIRE 17 -1 (-3175 3550)(-3725 3550);
FORCEPROP 2 LAST SIG_NAME M_G_BA<1:0>
J 0
(-3700 3560);
DISPLAY 0.617021 (-3700 3560);
PAINT ORANGE (-3700 3560);
WIRE 17 -1 (-3175 2975)(-3175 2950);
WIRE 17 -1 (-3175 2975)(-3725 2975);
FORCEPROP 2 LAST SIG_NAME M_G_CS_N<7:0>
J 0
(-3700 2985);
DISPLAY 0.617021 (-3700 2985);
PAINT ORANGE (-3700 2985);
WIRE 17 -1 (-3175 2900)(-3175 2950);
WIRE 17 -1 (-3175 2850)(-3175 2900);
WIRE 17 -1 (-3175 2800)(-3175 2850);
WIRE 17 -1 (-3175 3600)(-3175 3650);
WIRE 17 -1 (-3175 3650)(-3175 3700);
WIRE 17 -1 (-3175 3700)(-3175 3750);
WIRE 17 -1 (-3175 3750)(-3175 3800);
WIRE 17 -1 (-3175 2350)(-3175 2400);
WIRE 17 -1 (-3175 2300)(-3175 2350);
WIRE 17 -1 (-3175 2425)(-3175 2400);
WIRE 17 -1 (-3175 2425)(-3725 2425);
FORCEPROP 2 LAST SIG_NAME M_G_ECC<7:0>
J 0
(-3700 2435);
DISPLAY 0.617021 (-3700 2435);
PAINT ORANGE (-3700 2435);
WIRE 17 -1 (-3175 2250)(-3175 2300);
WIRE 17 -1 (-3175 2200)(-3175 2250);
WIRE 17 -1 (-3175 2150)(-3175 2200);
WIRE 17 -1 (-3175 2100)(-3175 2150);
WIRE 17 -1 (-3175 2050)(-3175 2100);
WIRE 17 -1 (-3175 2725)(-3175 2700);
WIRE 17 -1 (-3175 2725)(-3725 2725);
FORCEPROP 2 LAST SIG_NAME M_G_CKE<3:0>
J 0
(-3700 2735);
DISPLAY 0.617021 (-3700 2735);
PAINT ORANGE (-3700 2735);
WIRE 17 -1 (-3175 3350)(-3175 3400);
WIRE 17 -1 (-3175 3425)(-3175 3400);
WIRE 17 -1 (-3175 3425)(-3725 3425);
FORCEPROP 2 LAST SIG_NAME M_G_BG<1:0>
J 0
(-3700 3435);
DISPLAY 0.617021 (-3700 3435);
PAINT ORANGE (-3700 3435);
WIRE 17 -1 (-3175 3450)(-3175 3500);
WIRE 17 -1 (-3175 2500)(-3175 2550);
WIRE 17 -1 (-3175 2575)(-3175 2550);
WIRE 17 -1 (-3175 2575)(-3725 2575);
FORCEPROP 2 LAST SIG_NAME M_G_ODT<3:0>
J 0
(-3700 2585);
DISPLAY 0.617021 (-3700 2585);
PAINT ORANGE (-3700 2585);
WIRE 17 -1 (-3175 2650)(-3175 2700);
WIRE 16 -1 (-1000 1100)(-800 1100);
WIRE 16 -1 (-1000 1100)(-1000 1150);
WIRE 16 -1 (-1000 1150)(-800 1150);
WIRE 16 -1 (-1000 1150)(-1000 1200);
WIRE 16 -1 (-1000 1200)(-800 1200);
WIRE 16 -1 (-1000 1200)(-1000 1250);
WIRE 16 -1 (-1000 1250)(-1000 1300);
WIRE 16 -1 (-1000 1250)(-800 1250);
WIRE 16 -1 (-1000 1300)(-800 1300);
WIRE 16 -1 (-1000 1300)(-1000 1350);
WIRE 16 -1 (-1000 1350)(-800 1350);
WIRE 16 -1 (-1000 1350)(-1000 1400);
WIRE 16 -1 (-1000 1400)(-800 1400);
WIRE 16 -1 (-1000 1400)(-1000 1450);
WIRE 16 -1 (-1000 1450)(-800 1450);
WIRE 16 -1 (-1000 1450)(-1000 1500);
WIRE 16 -1 (-1000 1500)(-1000 1550);
WIRE 16 -1 (-1000 1500)(-800 1500);
WIRE 16 -1 (-1000 1550)(-800 1550);
WIRE 16 -1 (-1000 1550)(-1000 1600);
WIRE 16 -1 (-1000 1600)(-800 1600);
WIRE 16 -1 (-1000 1600)(-1000 1650);
WIRE 16 -1 (-1000 1650)(-800 1650);
WIRE 16 -1 (-1000 1650)(-1000 1700);
WIRE 16 -1 (-1000 1700)(-800 1700);
WIRE 16 -1 (-1000 1700)(-1000 1750);
WIRE 16 -1 (-1000 1750)(-1000 1800);
WIRE 16 -1 (-1000 1750)(-800 1750);
WIRE 16 -1 (-1000 1800)(-800 1800);
WIRE 16 -1 (-1000 1800)(-1000 1850);
WIRE 16 -1 (-1000 1850)(-800 1850);
WIRE 16 -1 (-1000 1850)(-1000 1900);
WIRE 16 -1 (-1000 1900)(-800 1900);
WIRE 16 -1 (-1000 1900)(-1000 1950);
WIRE 16 -1 (-1000 1950)(-800 1950);
WIRE 16 -1 (-1000 1950)(-1000 2000);
WIRE 16 -1 (-1000 2000)(-1000 2050);
WIRE 16 -1 (-1000 2000)(-800 2000);
WIRE 16 -1 (-1000 2050)(-800 2050);
WIRE 16 -1 (-1000 2050)(-1000 2100);
WIRE 16 -1 (-1000 2100)(-800 2100);
WIRE 16 -1 (-1000 2100)(-1000 2150);
WIRE 16 -1 (-1000 2150)(-800 2150);
WIRE 16 -1 (-1000 2150)(-1000 2200);
WIRE 16 -1 (-1000 2200)(-800 2200);
WIRE 16 -1 (-1000 2200)(-1000 2250);
WIRE 16 -1 (-1000 2250)(-800 2250);
WIRE 16 -1 (-1000 2250)(-1000 2300);
WIRE 16 -1 (-1000 2300)(-1000 2350);
WIRE 16 -1 (-1000 2300)(-800 2300);
WIRE 16 -1 (-1000 2350)(-800 2350);
WIRE 16 -1 (-1350 2350)(-1000 2350);
WIRE 16 -1 (-1350 2450)(-1350 2350);
WIRE 16 -1 (-1000 2450)(-800 2450);
WIRE 16 -1 (-1000 2450)(-1000 2500);
WIRE 16 -1 (-1000 2500)(-800 2500);
WIRE 16 -1 (-1150 2500)(-1000 2500);
WIRE 16 -1 (-1150 2600)(-1150 2500);
WIRE 16 -1 (2500 3300)(2500 3350);
WIRE 16 -1 (2500 3250)(2500 3300);
WIRE 16 -1 (2500 3300)(2300 3300);
WIRE 16 -1 (2500 3350)(2300 3350);
WIRE 16 -1 (2500 3200)(2500 3250);
WIRE 16 -1 (2500 3250)(2300 3250);
WIRE 16 -1 (2500 3150)(2500 3200);
WIRE 16 -1 (2500 3200)(2300 3200);
WIRE 16 -1 (2500 3100)(2500 3150);
WIRE 16 -1 (2500 3150)(2300 3150);
WIRE 16 -1 (2500 3100)(2300 3100);
WIRE 16 -1 (2500 3050)(2500 3100);
WIRE 16 -1 (2500 3000)(2500 3050);
WIRE 16 -1 (2500 3050)(2300 3050);
WIRE 16 -1 (2500 2950)(2500 3000);
WIRE 16 -1 (2500 3000)(2300 3000);
WIRE 16 -1 (2500 2900)(2500 2950);
WIRE 16 -1 (2500 2950)(2300 2950);
WIRE 16 -1 (2500 2850)(2500 2900);
WIRE 16 -1 (2500 2900)(2300 2900);
WIRE 16 -1 (2500 2800)(2500 2850);
WIRE 16 -1 (2500 2850)(2300 2850);
WIRE 16 -1 (2500 2750)(2500 2800);
WIRE 16 -1 (2500 2800)(2300 2800);
WIRE 16 -1 (2500 2700)(2500 2750);
WIRE 16 -1 (2500 2750)(2300 2750);
WIRE 16 -1 (2500 2650)(2500 2700);
WIRE 16 -1 (2500 2700)(2300 2700);
WIRE 16 -1 (2500 2600)(2500 2650);
WIRE 16 -1 (2500 2650)(2300 2650);
WIRE 16 -1 (2500 2600)(2300 2600);
WIRE 16 -1 (2500 2550)(2500 2600);
WIRE 16 -1 (2500 2500)(2500 2550);
WIRE 16 -1 (2500 2550)(2300 2550);
WIRE 16 -1 (2500 2450)(2500 2500);
WIRE 16 -1 (2500 2500)(2300 2500);
WIRE 16 -1 (2500 2400)(2500 2450);
WIRE 16 -1 (2500 2450)(2300 2450);
WIRE 16 -1 (2500 2350)(2500 2400);
WIRE 16 -1 (2500 2400)(2300 2400);
WIRE 16 -1 (2500 2300)(2500 2350);
WIRE 16 -1 (2500 2350)(2300 2350);
WIRE 16 -1 (2500 2250)(2500 2300);
WIRE 16 -1 (2500 2300)(2300 2300);
WIRE 16 -1 (2500 2200)(2500 2250);
WIRE 16 -1 (2500 2250)(2300 2250);
WIRE 16 -1 (2500 2150)(2500 2200);
WIRE 16 -1 (2500 2200)(2300 2200);
WIRE 16 -1 (2500 2100)(2500 2150);
WIRE 16 -1 (2500 2150)(2300 2150);
WIRE 16 -1 (2500 2050)(2500 2100);
WIRE 16 -1 (2500 2100)(2300 2100);
WIRE 16 -1 (2500 2050)(2300 2050);
WIRE 16 -1 (2500 2000)(2500 2050);
WIRE 16 -1 (2500 1950)(2500 2000);
WIRE 16 -1 (2500 2000)(2300 2000);
WIRE 16 -1 (2500 1900)(2500 1950);
WIRE 16 -1 (2500 1950)(2300 1950);
WIRE 16 -1 (2500 1850)(2500 1900);
WIRE 16 -1 (2500 1900)(2300 1900);
WIRE 16 -1 (2500 1800)(2500 1850);
WIRE 16 -1 (2500 1850)(2300 1850);
WIRE 16 -1 (2500 1750)(2500 1800);
WIRE 16 -1 (2500 1800)(2300 1800);
WIRE 16 -1 (2500 1700)(2500 1750);
WIRE 16 -1 (2500 1750)(2300 1750);
WIRE 16 -1 (2500 1650)(2500 1700);
WIRE 16 -1 (2500 1700)(2300 1700);
WIRE 16 -1 (2500 1600)(2500 1650);
WIRE 16 -1 (2500 1650)(2300 1650);
WIRE 16 -1 (2500 1550)(2500 1600);
WIRE 16 -1 (2500 1600)(2300 1600);
WIRE 16 -1 (2500 1550)(2300 1550);
WIRE 16 -1 (2500 1500)(2500 1550);
WIRE 16 -1 (2500 1450)(2500 1500);
WIRE 16 -1 (2500 1500)(2300 1500);
WIRE 16 -1 (2500 1400)(2500 1450);
WIRE 16 -1 (2500 1450)(2300 1450);
WIRE 16 -1 (2500 1350)(2500 1400);
WIRE 16 -1 (2500 1400)(2300 1400);
WIRE 16 -1 (2500 1300)(2500 1350);
WIRE 16 -1 (2500 1350)(2300 1350);
WIRE 16 -1 (2500 1250)(2500 1300);
WIRE 16 -1 (2500 1300)(2300 1300);
WIRE 16 -1 (2500 1200)(2500 1250);
WIRE 16 -1 (2500 1250)(2300 1250);
WIRE 16 -1 (2500 1150)(2500 1200);
WIRE 16 -1 (2500 1200)(2300 1200);
WIRE 16 -1 (2500 1100)(2500 1150);
WIRE 16 -1 (2500 1150)(2300 1150);
WIRE 16 -1 (2500 1050)(2500 1100);
WIRE 16 -1 (2500 1100)(2300 1100);
WIRE 16 -1 (2500 1050)(2300 1050);
WIRE 16 -1 (2500 950)(2500 1050);
WIRE 16 -1 (-3025 1475)(-2875 1475);
WIRE 16 -1 (-3025 1525)(-3025 1475);
WIRE 16 -1 (-2875 1525)(-3025 1525);
WIRE 16 -1 (-3025 1575)(-3025 1525);
WIRE 16 -1 (-2875 1575)(-3025 1575);
WIRE 16 -1 (-3025 1575)(-5075 1575);
WIRE 16 -1 (-5075 1575)(-5075 1475);
WIRE 16 -1 (-4425 975)(-4425 875);
WIRE 16 -1 (-1000 2600)(-800 2600);
WIRE 16 -1 (-1000 2600)(-1000 2650);
WIRE 16 -1 (-1000 2650)(-800 2650);
WIRE 16 -1 (-1000 2650)(-1000 2700);
WIRE 16 -1 (-1000 2700)(-800 2700);
WIRE 16 -1 (-1000 2700)(-1000 2750);
WIRE 16 -1 (-1000 2750)(-800 2750);
WIRE 16 -1 (-1000 2750)(-1000 2800);
WIRE 16 -1 (-1000 2900)(-1000 2800);
WIRE 16 -1 (-1000 2800)(-800 2800);
WIRE 16 -1 (-2875 1625)(-5075 1625);
WIRE 16 -1 (-5075 1725)(-5075 1625);
WIRE 16 -1 (200 2750)(400 2750);
WIRE 16 -1 (400 2750)(400 2800);
WIRE 16 -1 (200 2800)(400 2800);
WIRE 16 -1 (400 2800)(400 2875);
WIRE 16 -1 (1100 3350)(1300 3350);
WIRE 16 -1 (1100 3300)(1100 3350);
WIRE 16 -1 (1100 3300)(1300 3300);
WIRE 16 -1 (1100 3250)(1100 3300);
WIRE 16 -1 (1100 3250)(1300 3250);
WIRE 16 -1 (1100 3200)(1100 3250);
WIRE 16 -1 (1100 3200)(1300 3200);
WIRE 16 -1 (1100 3150)(1100 3200);
WIRE 16 -1 (1100 3150)(1300 3150);
WIRE 16 -1 (1100 3100)(1100 3150);
WIRE 16 -1 (1100 3100)(1300 3100);
WIRE 16 -1 (1100 3050)(1100 3100);
WIRE 16 -1 (1100 3050)(1300 3050);
WIRE 16 -1 (1100 3000)(1100 3050);
WIRE 16 -1 (1100 3000)(1300 3000);
WIRE 16 -1 (1100 2950)(1100 3000);
WIRE 16 -1 (1100 2950)(1300 2950);
WIRE 16 -1 (1100 2900)(1100 2950);
WIRE 16 -1 (1100 2900)(1300 2900);
WIRE 16 -1 (1100 2850)(1100 2900);
WIRE 16 -1 (1100 2850)(1300 2850);
WIRE 16 -1 (1100 2800)(1100 2850);
WIRE 16 -1 (1100 2800)(1300 2800);
WIRE 16 -1 (1100 2750)(1100 2800);
WIRE 16 -1 (1100 2750)(1300 2750);
WIRE 16 -1 (1100 2700)(1100 2750);
WIRE 16 -1 (1100 2700)(1300 2700);
WIRE 16 -1 (1100 2650)(1100 2700);
WIRE 16 -1 (1100 2650)(1300 2650);
WIRE 16 -1 (1100 2600)(1100 2650);
WIRE 16 -1 (1100 2600)(1300 2600);
WIRE 16 -1 (1100 2550)(1100 2600);
WIRE 16 -1 (1100 2550)(1300 2550);
WIRE 16 -1 (1100 2500)(1100 2550);
WIRE 16 -1 (1100 2500)(1300 2500);
WIRE 16 -1 (1100 2450)(1100 2500);
WIRE 16 -1 (1100 2450)(1300 2450);
WIRE 16 -1 (1100 2400)(1100 2450);
WIRE 16 -1 (1100 2400)(1300 2400);
WIRE 16 -1 (1100 2350)(1100 2400);
WIRE 16 -1 (1100 2350)(1300 2350);
WIRE 16 -1 (1100 2300)(1100 2350);
WIRE 16 -1 (1100 2300)(1300 2300);
WIRE 16 -1 (1100 2250)(1100 2300);
WIRE 16 -1 (1100 2250)(1300 2250);
WIRE 16 -1 (1100 2200)(1100 2250);
WIRE 16 -1 (1100 2200)(1300 2200);
WIRE 16 -1 (1100 2150)(1100 2200);
WIRE 16 -1 (1100 2150)(1300 2150);
WIRE 16 -1 (1100 2100)(1100 2150);
WIRE 16 -1 (1100 2100)(1300 2100);
WIRE 16 -1 (1100 2050)(1100 2100);
WIRE 16 -1 (1100 2050)(1300 2050);
WIRE 16 -1 (1100 2000)(1100 2050);
WIRE 16 -1 (1100 2000)(1300 2000);
WIRE 16 -1 (1100 1950)(1100 2000);
WIRE 16 -1 (1100 1950)(1300 1950);
WIRE 16 -1 (1100 1900)(1100 1950);
WIRE 16 -1 (1100 1900)(1300 1900);
WIRE 16 -1 (1100 1850)(1100 1900);
WIRE 16 -1 (1100 1850)(1300 1850);
WIRE 16 -1 (1100 1800)(1100 1850);
WIRE 16 -1 (1100 1800)(1300 1800);
WIRE 16 -1 (1100 1750)(1100 1800);
WIRE 16 -1 (1100 1750)(1300 1750);
WIRE 16 -1 (1100 1700)(1100 1750);
WIRE 16 -1 (1100 1700)(1300 1700);
WIRE 16 -1 (1100 1650)(1100 1700);
WIRE 16 -1 (1100 1650)(1300 1650);
WIRE 16 -1 (1100 1600)(1100 1650);
WIRE 16 -1 (1100 1600)(1300 1600);
WIRE 16 -1 (1100 1550)(1100 1600);
WIRE 16 -1 (1100 1550)(1300 1550);
WIRE 16 -1 (1100 1500)(1100 1550);
WIRE 16 -1 (1100 1500)(1300 1500);
WIRE 16 -1 (1100 1450)(1100 1500);
WIRE 16 -1 (1100 1450)(1300 1450);
WIRE 16 -1 (1100 1400)(1100 1450);
WIRE 16 -1 (1100 1400)(1300 1400);
WIRE 16 -1 (1100 1350)(1100 1400);
WIRE 16 -1 (1100 1350)(1300 1350);
WIRE 16 -1 (1100 1300)(1100 1350);
WIRE 16 -1 (1100 1300)(1300 1300);
WIRE 16 -1 (1100 1250)(1100 1300);
WIRE 16 -1 (1100 1250)(1300 1250);
WIRE 16 -1 (1100 1200)(1100 1250);
WIRE 16 -1 (1100 1200)(1300 1200);
WIRE 16 -1 (1100 1150)(1100 1200);
WIRE 16 -1 (1100 1150)(1300 1150);
WIRE 16 -1 (1100 1100)(1100 1150);
WIRE 16 -1 (1100 1100)(1300 1100);
WIRE 16 -1 (1100 1050)(1100 1100);
WIRE 16 -1 (1100 1050)(1300 1050);
WIRE 16 -1 (1100 950)(1100 1050);
WIRE 16 -1 (-2875 1275)(-4425 1275);
FORCEPROP 2 LAST SIG_NAME M_G_VREF
J 0
(-4175 1285);
DISPLAY 0.617021 (-4175 1285);
PAINT ORANGE (-4175 1285);
WIRE 16 -1 (-4425 1275)(-4425 1175);
WIRE 16 -1 (-4525 1275)(-4425 1275);
WIRE 16 -1 (-3725 1125)(-2875 1125);
FORCEPROP 2 LAST SIG_NAME TP_CH_G_DIMM_G0_RFU_1
J 0
(-3675 1135);
DISPLAY 0.617021 (-3675 1135);
PAINT ORANGE (-3675 1135);
FORCEPROP 2 LASTPROP $XRERR UNIQUE?
J 0
(-3965 1125);
DISPLAY 0.638298 (-3965 1125);
PAINT MONO (-3965 1125);
DISPLAY INVISIBLE (-3965 1125);
WIRE 16 -1 (-3725 1175)(-2875 1175);
FORCEPROP 2 LAST SIG_NAME TP_CH_G_DIMM_G0_RFU_2
J 0
(-3675 1185);
DISPLAY 0.617021 (-3675 1185);
PAINT ORANGE (-3675 1185);
FORCEPROP 2 LASTPROP $XRERR UNIQUE?
J 0
(-3965 1175);
DISPLAY 0.638298 (-3965 1175);
PAINT MONO (-3965 1175);
DISPLAY INVISIBLE (-3965 1175);
WIRE 16 -1 (-2875 2025)(-3075 2025);
WIRE 16 -1 (-3725 1075)(-2875 1075);
FORCEPROP 2 LAST SIG_NAME TP_CH_G_DIMM_G0_RFU_0
J 0
(-3675 1085);
DISPLAY 0.617021 (-3675 1085);
PAINT ORANGE (-3675 1085);
FORCEPROP 2 LASTPROP $XRERR UNIQUE?
J 0
(-3965 1075);
DISPLAY 0.638298 (-3965 1075);
PAINT MONO (-3965 1075);
DISPLAY INVISIBLE (-3965 1075);
WIRE 16 -1 (-2875 1725)(-3875 1725);
FORCEPROP 2 LAST SIG_NAME M_G_ACT_N
J 0
(-3825 1735);
DISPLAY 0.617021 (-3825 1735);
PAINT ORANGE (-3825 1735);
WIRE 16 -1 (-2875 1775)(-3900 1775);
FORCEPROP 2 LAST SIG_NAME M_G_ALERT_N
J 0
(-3850 1785);
DISPLAY 0.617021 (-3850 1785);
PAINT ORANGE (-3850 1785);
WIRE 16 -1 (-3725 1425)(-2875 1425);
WIRE 16 -1 (-3725 1375)(-2875 1375);
FORCEPROP 2 LAST SIG_NAME SMB_DDR_GHJ_VPP_SCL
J 0
(-3685 1385);
DISPLAY 0.617021 (-3685 1385);
PAINT ORANGE (-3685 1385);
WIRE 16 -1 (-3725 975)(-2875 975);
FORCEPROP 2 LAST SIG_NAME FM_ADR_COMPLETE_GHJ_N
J 0
(-3675 985);
DISPLAY 0.617021 (-3675 985);
PAINT ORANGE (-3675 985);
WIRE 16 -1 (-3325 2075)(-4050 2075);
FORCEPROP 2 LAST SIG_NAME FM_DIMM_EVENT_COD_N
J 0
(-4041 2090);
DISPLAY 0.617021 (-4041 2090);
PAINT ORANGE (-4041 2090);
WIRE 16 -1 (-3325 1825)(-3325 2075);
WIRE 16 -1 (-3325 1825)(-2875 1825);
WIRE 16 -1 (-3225 2375)(-3725 2375);
FORCEPROP 2 LAST SIG_NAME M_G_PAR
J 0
(-3700 2385);
DISPLAY 0.617021 (-3700 2385);
PAINT ORANGE (-3700 2385);
WIRE 16 -1 (-3225 1925)(-3225 2375);
WIRE 16 -1 (-2875 1925)(-3225 1925);
WIRE 16 -1 (-3275 2325)(-3725 2325);
FORCEPROP 2 LAST SIG_NAME M_GHJ_RST_N
J 0
(-3700 2335);
DISPLAY 0.617021 (-3700 2335);
PAINT ORANGE (-3700 2335);
WIRE 16 -1 (-3275 1875)(-3275 2325);
WIRE 16 -1 (-2875 1875)(-3275 1875);
WIRE 16 -1 (-2875 2775)(-3075 2775);
WIRE 16 -1 (-2875 2625)(-3075 2625);
WIRE 16 -1 (-2875 2525)(-3075 2525);
WIRE 16 -1 (-2875 2475)(-3075 2475);
WIRE 16 -1 (-2875 2375)(-3075 2375);
WIRE 16 -1 (-2875 4075)(-3075 4075);
WIRE 16 -1 (-2875 3675)(-3075 3675);
WIRE 16 -1 (-2875 3425)(-3075 3425);
WIRE 16 -1 (-2875 3375)(-3075 3375);
WIRE 16 -1 (-2875 3325)(-3075 3325);
WIRE 16 -1 (-2875 3225)(-3075 3225);
WIRE 16 -1 (-2875 2675)(-3075 2675);
WIRE 16 -1 (-2875 2075)(-3075 2075);
WIRE 16 -1 (-2875 2125)(-3075 2125);
WIRE 16 -1 (-2875 2175)(-3075 2175);
WIRE 16 -1 (-2875 2225)(-3075 2225);
WIRE 16 -1 (-2875 2275)(-3075 2275);
WIRE 16 -1 (-2875 2325)(-3075 2325);
WIRE 16 -1 (-2875 4025)(-3075 4025);
WIRE 16 -1 (-2875 3975)(-3075 3975);
WIRE 16 -1 (-2875 3925)(-3075 3925);
WIRE 16 -1 (-2875 3875)(-3075 3875);
WIRE 16 -1 (-2875 3825)(-3075 3825);
WIRE 16 -1 (-2875 3775)(-3075 3775);
WIRE 16 -1 (-2875 3725)(-3075 3725);
WIRE 16 -1 (-2875 3625)(-3075 3625);
WIRE 16 -1 (-2875 3575)(-3075 3575);
WIRE 16 -1 (-2875 2825)(-3075 2825);
WIRE 16 -1 (-2875 2875)(-3075 2875);
WIRE 16 -1 (-2875 2925)(-3075 2925);
WIRE 16 -1 (-2875 3475)(-3075 3475);
WIRE 16 -1 (-2875 3075)(-3275 3075);
WIRE 16 -1 (-2875 3125)(-3075 3125);
WIRE 16 -1 (-2875 3175)(-3275 3175);
WIRE 16 -1 (-3025 2975)(-2875 2975);
WIRE 16 -1 (-3025 3025)(-3025 2975);
WIRE 16 -1 (-3025 3025)(-3725 3025);
FORCEPROP 2 LAST SIG_NAME M_G_C<2>
J 0
(-3700 3035);
DISPLAY 0.617021 (-3700 3035);
PAINT ORANGE (-3700 3035);
WIRE 16 -1 (-1675 1475)(-1875 1475);
WIRE 16 -1 (-1675 1425)(-1875 1425);
WIRE 16 -1 (-1675 1375)(-1875 1375);
WIRE 16 -1 (-1675 1275)(-1875 1275);
WIRE 16 -1 (-1675 1325)(-1875 1325);
WIRE 16 -1 (-1675 1525)(-1875 1525);
WIRE 16 -1 (-1675 2025)(-1875 2025);
WIRE 16 -1 (-1675 1575)(-1875 1575);
WIRE 16 -1 (-1675 1675)(-1875 1675);
WIRE 16 -1 (-1675 1725)(-1875 1725);
WIRE 16 -1 (-1675 1775)(-1875 1775);
WIRE 16 -1 (-1675 1825)(-1875 1825);
WIRE 16 -1 (-1675 1875)(-1875 1875);
WIRE 16 -1 (-1675 1925)(-1875 1925);
WIRE 16 -1 (-1675 1975)(-1875 1975);
WIRE 16 -1 (-1675 1625)(-1875 1625);
WIRE 16 -1 (-1675 2175)(-1875 2175);
WIRE 16 -1 (-1675 2225)(-1875 2225);
WIRE 16 -1 (-1675 2275)(-1875 2275);
WIRE 16 -1 (-1675 2325)(-1875 2325);
WIRE 16 -1 (-1675 2375)(-1875 2375);
WIRE 16 -1 (-1675 2425)(-1875 2425);
WIRE 16 -1 (-1675 2475)(-1875 2475);
WIRE 16 -1 (-1675 2525)(-1875 2525);
WIRE 16 -1 (-1675 2075)(-1875 2075);
WIRE 16 -1 (-1675 2125)(-1875 2125);
WIRE 16 -1 (-1675 2575)(-1875 2575);
WIRE 16 -1 (-1675 3025)(-1875 3025);
WIRE 16 -1 (-1675 2775)(-1875 2775);
WIRE 16 -1 (-1675 2825)(-1875 2825);
WIRE 16 -1 (-1675 2875)(-1875 2875);
WIRE 16 -1 (-1675 2925)(-1875 2925);
WIRE 16 -1 (-1675 2975)(-1875 2975);
WIRE 16 -1 (-1675 2675)(-1875 2675);
WIRE 16 -1 (-1675 2725)(-1875 2725);
WIRE 16 -1 (-1675 2625)(-1875 2625);
WIRE 16 -1 (-1675 3175)(-1875 3175);
WIRE 16 -1 (-1675 3075)(-1875 3075);
WIRE 16 -1 (-1675 3125)(-1875 3125);
WIRE 16 -1 (-1675 3275)(-1875 3275);
WIRE 16 -1 (-1675 3375)(-1875 3375);
WIRE 16 -1 (-1675 3525)(-1875 3525);
WIRE 16 -1 (-1675 3575)(-1875 3575);
WIRE 16 -1 (-1675 3475)(-1875 3475);
WIRE 16 -1 (-1675 3425)(-1875 3425);
WIRE 16 -1 (-1675 3325)(-1875 3325);
WIRE 16 -1 (-1675 3225)(-1875 3225);
WIRE 16 -1 (-1675 3625)(-1875 3625);
WIRE 16 -1 (-1675 3825)(-1875 3825);
WIRE 16 -1 (-1675 3875)(-1875 3875);
WIRE 16 -1 (-1675 3925)(-1875 3925);
WIRE 16 -1 (-1675 3975)(-1875 3975);
WIRE 16 -1 (-1675 4025)(-1875 4025);
WIRE 16 -1 (-1675 4075)(-1875 4075);
WIRE 16 -1 (-1675 3775)(-1875 3775);
WIRE 16 -1 (-1675 3725)(-1875 3725);
WIRE 16 -1 (-1675 3675)(-1875 3675);
WIRE 16 -1 (-2875 4375)(-3075 4375);
WIRE 16 -1 (-2875 4325)(-3075 4325);
WIRE 16 -1 (-2875 4275)(-3075 4275);
WIRE 16 -1 (-2875 4125)(-3075 4125);
WIRE 16 -1 (-2875 4425)(-3075 4425);
WIRE 16 -1 (-2875 4225)(-3075 4225);
WIRE 16 -1 (-2875 4175)(-3075 4175);
WIRE 16 -1 (-1675 4425)(-1875 4425);
WIRE 16 -1 (-1675 4375)(-1875 4375);
WIRE 16 -1 (-1675 4325)(-1875 4325);
WIRE 16 -1 (-1675 4175)(-1875 4175);
WIRE 16 -1 (-1675 4125)(-1875 4125);
WIRE 16 -1 (-1675 4225)(-1875 4225);
WIRE 16 -1 (-1675 4275)(-1875 4275);
WIRE 16 -1 (650 4050)(450 4050);
WIRE 16 -1 (850 4000)(450 4000);
WIRE 16 -1 (650 3950)(450 3950);
WIRE 16 -1 (850 3900)(450 3900);
WIRE 16 -1 (650 3850)(450 3850);
WIRE 16 -1 (850 3800)(450 3800);
WIRE 16 -1 (650 3750)(450 3750);
WIRE 16 -1 (850 3700)(450 3700);
WIRE 16 -1 (650 3650)(450 3650);
WIRE 16 -1 (850 3600)(450 3600);
WIRE 16 -1 (650 3550)(450 3550);
WIRE 16 -1 (850 3500)(450 3500);
WIRE 16 -1 (650 3450)(450 3450);
WIRE 16 -1 (850 3400)(450 3400);
WIRE 16 -1 (650 3350)(450 3350);
WIRE 16 -1 (850 3300)(450 3300);
WIRE 16 -1 (650 5050)(450 5050);
WIRE 16 -1 (650 4250)(450 4250);
WIRE 16 -1 (850 4200)(450 4200);
WIRE 16 -1 (650 4150)(450 4150);
WIRE 16 -1 (850 4100)(450 4100);
WIRE 16 -1 (850 5000)(450 5000);
WIRE 16 -1 (650 4950)(450 4950);
WIRE 16 -1 (850 4900)(450 4900);
WIRE 16 -1 (650 4850)(450 4850);
WIRE 16 -1 (850 4800)(450 4800);
WIRE 16 -1 (650 4750)(450 4750);
WIRE 16 -1 (850 4700)(450 4700);
WIRE 16 -1 (650 4650)(450 4650);
WIRE 16 -1 (850 4600)(450 4600);
WIRE 16 -1 (650 4550)(450 4550);
WIRE 16 -1 (850 4500)(450 4500);
WIRE 16 -1 (650 4450)(450 4450);
WIRE 16 -1 (850 4400)(450 4400);
WIRE 16 -1 (650 4350)(450 4350);
WIRE 16 -1 (850 4300)(450 4300);
DOT 1 (400 2800);
DOT 1 (-3025 1575);
DOT 1 (-1000 2800);
DOT 1 (-4425 1275);
DOT 1 (-3025 1525);
DOT 1 (-1000 2650);
DOT 1 (-1000 1200);
DOT 1 (-1000 1250);
DOT 1 (-1000 1150);
DOT 1 (-1000 1350);
DOT 1 (-1000 1300);
DOT 1 (-1000 1500);
DOT 1 (-1000 1450);
DOT 1 (-1000 1400);
DOT 1 (-1000 1550);
DOT 1 (-1000 1650);
DOT 1 (-1000 1700);
DOT 1 (-1000 1750);
DOT 1 (-1000 1800);
DOT 1 (-1000 1850);
DOT 1 (-1000 1900);
DOT 1 (-1000 2000);
DOT 1 (-1000 1950);
DOT 1 (-1000 2100);
DOT 1 (-1000 2050);
DOT 1 (-1000 2150);
DOT 1 (-1000 2350);
DOT 1 (-1000 2300);
DOT 1 (-1000 2700);
DOT 1 (-1000 2750);
DOT 1 (2500 3300);
DOT 1 (2500 3250);
DOT 1 (2500 3200);
DOT 1 (2500 3150);
DOT 1 (2500 3100);
DOT 1 (2500 3050);
DOT 1 (2500 3000);
DOT 1 (2500 2950);
DOT 1 (2500 2900);
DOT 1 (2500 2850);
DOT 1 (2500 2800);
DOT 1 (2500 2750);
DOT 1 (2500 2650);
DOT 1 (2500 2600);
DOT 1 (2500 2550);
DOT 1 (2500 2500);
DOT 1 (2500 2450);
DOT 1 (2500 2400);
DOT 1 (2500 2350);
DOT 1 (2500 2300);
DOT 1 (2500 2250);
DOT 1 (2500 2200);
DOT 1 (2500 2150);
DOT 1 (2500 2100);
DOT 1 (2500 2050);
DOT 1 (2500 2000);
DOT 1 (2500 1950);
DOT 1 (2500 1900);
DOT 1 (2500 1850);
DOT 1 (2500 1800);
DOT 1 (2500 1750);
DOT 1 (2500 1700);
DOT 1 (2500 1650);
DOT 1 (2500 1600);
DOT 1 (2500 1550);
DOT 1 (2500 1500);
DOT 1 (2500 1450);
DOT 1 (2500 1400);
DOT 1 (2500 1350);
DOT 1 (2500 1300);
DOT 1 (2500 1250);
DOT 1 (2500 1200);
DOT 1 (2500 1150);
DOT 1 (2500 1100);
DOT 1 (2500 1050);
DOT 1 (1100 3300);
DOT 1 (1100 3100);
DOT 1 (1100 3150);
DOT 1 (1100 3050);
DOT 1 (1100 3000);
DOT 1 (1100 2950);
DOT 1 (1100 2850);
DOT 1 (1100 2900);
DOT 1 (1100 2800);
DOT 1 (1100 2750);
DOT 1 (1100 2700);
DOT 1 (1100 2600);
DOT 1 (1100 2650);
DOT 1 (1100 2550);
DOT 1 (1100 2500);
DOT 1 (1100 2450);
DOT 1 (1100 2350);
DOT 1 (1100 2400);
DOT 1 (1100 2300);
DOT 1 (1100 2250);
DOT 1 (1100 2200);
DOT 1 (1100 2150);
DOT 1 (1100 2100);
DOT 1 (1100 2050);
DOT 1 (1100 2000);
DOT 1 (1100 1950);
DOT 1 (1100 1900);
DOT 1 (1100 1850);
DOT 1 (1100 1800);
DOT 1 (1100 1700);
DOT 1 (1100 1750);
DOT 1 (1100 1650);
DOT 1 (1100 1550);
DOT 1 (1100 1600);
DOT 1 (1100 1450);
DOT 1 (1100 1500);
DOT 1 (1100 1400);
DOT 1 (1100 1350);
DOT 1 (1100 1300);
DOT 1 (1100 1200);
DOT 1 (1100 1250);
DOT 1 (1100 1150);
DOT 1 (1100 1100);
DOT 1 (1100 1050);
DOT 1 (1100 3200);
DOT 1 (2500 2700);
DOT 1 (1100 3250);
DOT 1 (-1000 1600);
DOT 1 (-1000 2200);
DOT 1 (-1000 2250);
DOT 1 (-1000 2500);
FORCENOTE
SMBUS ADDR: 0XA0
(-5300 600) 0;
DISPLAY LEFT (-5300 600);
DISPLAY 1.957447 (-5300 600);
PAINT PURPLE (-5300 600);
FORCENOTE
PLACE CAP NEAR DIMM CONNECTOR
(-5288 702) 0;
DISPLAY LEFT (-5288 702);
DISPLAY 1.957447 (-5288 702);
PAINT PURPLE (-5288 702);
QUIT
